FILE_TYPE = MACRO_DRAWING;
SET COLOR_WIRE YELLOW;
SET COLOR_PROP MONO;
SET COLOR_DOT WHITE;
SET COLOR_ARC YELLOW;
SET COLOR_BODY GREEN;
SET COLOR_NOTE MONO;
SET PROP_DISPLAY VALUE;
SET PAGE_NUMBER P84;
FORCEADD GND..1
R 2
(-3500 1475);
FORCEPROP 3 LASTPIN (-3500 1525) SIG_NAME GND\g
J 0
(-3490 1535);
DISPLAY 0.659574 (-3490 1535);
PAINT MONO (-3490 1535);
DISPLAY INVISIBLE (-3490 1535);
FORCEPROP 1 LAST VOLTAGE 0
J 0
(-3500 1475);
PAINT SKYBLUE (-3500 1475);
DISPLAY INVISIBLE (-3500 1475);
FORCEPROP 1 LAST SIZE 1B
J 2
(-3575 1425);
DISPLAY 1.170213 (-3575 1425);
PAINT GREEN (-3575 1425);
DISPLAY INVISIBLE (-3575 1425);
FORCEPROP 2 LAST CDS_LIB mstr_symbols
J 0
(-3500 1475);
DISPLAY 0.787234 (-3500 1475);
PAINT MONO (-3500 1475);
DISPLAY INVISIBLE (-3500 1475);
FORCEPROP 2 LAST BOM_COST MEM
J 0
(-3500 1480);
PAINT ORANGE (-3500 1480);
DISPLAY INVISIBLE (-3500 1480);
FORCEPROP 1 LAST BODY_TYPE PLUMBING
J 2
(-3455 1432);
DISPLAY 0.340426 (-3455 1432);
PAINT GREEN (-3455 1432);
DISPLAY INVISIBLE (-3455 1432);
FORCEPROP 1 LAST PATH I1
J 2
(-3575 1475);
DISPLAY 0.872340 (-3575 1475);
PAINT AQUA (-3575 1475);
DISPLAY INVISIBLE (-3575 1475);
FORCEPROP 2 LAST ROOM DDR4_CH_C
J 0
(-3500 1480);
PAINT ORANGE (-3500 1480);
DISPLAY INVISIBLE (-3500 1480);
FORCEPROP 1 LAST HDL_POWER GND
J 2
(-3500 1625);
DISPLAY 0.553191 (-3500 1625);
PAINT GREEN (-3500 1625);
DISPLAY INVISIBLE (-3500 1625);
FORCEADD OFFPAGE..1
(-2650 3325);
FORCEPROP 2 LAST $XR0 60 
J 0
(-2901 3325);
DISPLAY 0.638298 (-2901 3325);
PAINT MONO (-2901 3325);
FORCEPROP 2 LAST $XR1 83 
J 0
(-2991 3325);
DISPLAY 0.638298 (-2991 3325);
PAINT MONO (-2991 3325);
FORCEPROP 2 LAST CDS_LIB mstr_standard
J 0
(-2650 3325);
DISPLAY 0.787234 (-2650 3325);
PAINT MONO (-2650 3325);
DISPLAY INVISIBLE (-2650 3325);
FORCEPROP 1 LAST OFFPAGE TRUE
J 0
(-2325 3200);
DISPLAY 0.936170 (-2325 3200);
PAINT GREEN (-2325 3200);
DISPLAY INVISIBLE (-2325 3200);
FORCEPROP 1 LAST COMMENT_BODY TRUE
J 0
(-2525 3225);
DISPLAY 0.936170 (-2525 3225);
PAINT GREEN (-2525 3225);
DISPLAY INVISIBLE (-2525 3225);
FORCEPROP 2 LAST PATH I10
J 0
(-2900 3375);
DISPLAY 1.021277 (-2900 3375);
PAINT ORANGE (-2900 3375);
DISPLAY INVISIBLE (-2900 3375);
FORCEADD PVTT_KLM..1
(600 2425);
FORCEPROP 3 LASTPIN (600 2375) SIG_NAME PVTT_KLM\g
J 0
(610 2385);
DISPLAY 0.659574 (610 2385);
PAINT MONO (610 2385);
DISPLAY INVISIBLE (610 2385);
FORCEPROP 1 LAST VOLTAGE 0.6V
J 0
(555 2382);
DISPLAY 0.340426 (555 2382);
PAINT SKYBLUE (555 2382);
DISPLAY INVISIBLE (555 2382);
FORCEPROP 2 LAST BOM_COST MEM
J 0
(600 2430);
PAINT ORANGE (600 2430);
DISPLAY INVISIBLE (600 2430);
FORCEPROP 2 LAST CDS_LIB mstr_symbols
J 0
(600 2425);
PAINT ORANGE (600 2425);
DISPLAY INVISIBLE (600 2425);
FORCEPROP 1 LAST BODY_TYPE PLUMBING
J 0
(555 2382);
DISPLAY 0.340426 (555 2382);
PAINT GREEN (555 2382);
DISPLAY INVISIBLE (555 2382);
FORCEPROP 1 LAST PATH I100
J 0
(650 2450);
DISPLAY 0.872340 (650 2450);
PAINT AQUA (650 2450);
DISPLAY INVISIBLE (650 2450);
FORCEPROP 2 LAST ROOM DDR4_CH_C
J 0
(600 2525);
DISPLAY 0.787234 (600 2525);
PAINT ORANGE (600 2525);
DISPLAY INVISIBLE (600 2525);
FORCEPROP 1 LAST HDL_POWER PVTT_KLM
J 1
(600 2475);
DISPLAY 0.872340 (600 2475);
PAINT GREEN (600 2475);
DISPLAY INVISIBLE (600 2475);
FORCEADD PVPP_KLM..1
(750 2725);
FORCEPROP 3 LASTPIN (750 2675) SIG_NAME PVPP_KLM\g
J 0
(760 2685);
DISPLAY 0.659574 (760 2685);
PAINT MONO (760 2685);
DISPLAY INVISIBLE (760 2685);
FORCEPROP 1 LAST VOLTAGE 2.5V
J 0
(705 2682);
DISPLAY 0.340426 (705 2682);
PAINT SKYBLUE (705 2682);
DISPLAY INVISIBLE (705 2682);
FORCEPROP 0 LAST BOM_COST MEM
J 0
(750 2825);
PAINT ORANGE (750 2825);
DISPLAY INVISIBLE (750 2825);
FORCEPROP 2 LAST CDS_LIB mstr_symbols
J 0
(750 2725);
PAINT ORANGE (750 2725);
DISPLAY INVISIBLE (750 2725);
FORCEPROP 1 LAST BODY_TYPE PLUMBING
J 0
(705 2682);
DISPLAY 0.340426 (705 2682);
PAINT GREEN (705 2682);
DISPLAY INVISIBLE (705 2682);
FORCEPROP 1 LAST PATH I101
J 0
(800 2750);
DISPLAY 0.872340 (800 2750);
PAINT AQUA (800 2750);
DISPLAY INVISIBLE (800 2750);
FORCEPROP 2 LAST ROOM DDR4_CH_C
J 0
(750 2825);
PAINT ORANGE (750 2825);
DISPLAY INVISIBLE (750 2825);
FORCEPROP 1 LAST HDL_POWER PVPP_KLM
J 1
(750 2775);
DISPLAY 0.872340 (750 2775);
PAINT GREEN (750 2775);
DISPLAY INVISIBLE (750 2775);
FORCEADD SCONN288_H44441003..2
(1600 3975);
FORCEPROP 1 LAST LOCATION J9M1
J 0
(1200 5075);
DISPLAY 0.617021 (1200 5075);
PAINT AQUA (1200 5075);
FORCEPROP 1 LAST PART_NUMBER H44441-003
J 0
(1200 2875);
DISPLAY 0.617021 (1200 2875);
PAINT BLUE (1200 2875);
FORCEPROP 1 LAST MATERIAL SCONN
J 0
(1200 5025);
DISPLAY 0.617021 (1200 5025);
PAINT SKYBLUE (1200 5025);
FORCEPROP 2 LASTPIN (2050 4825) $PN 51
J 0
(2060 4835);
DISPLAY 0.617021 (2060 4835);
PAINT ORANGE (2060 4835);
FORCEPROP 2 LASTPIN (2050 4775) $PN 52
J 0
(2060 4785);
DISPLAY 0.617021 (2060 4785);
PAINT ORANGE (2060 4785);
FORCEPROP 2 LASTPIN (2050 4725) $PN 132
J 0
(2060 4735);
DISPLAY 0.617021 (2060 4735);
PAINT ORANGE (2060 4735);
FORCEPROP 2 LASTPIN (2050 4675) $PN 133
J 0
(2060 4685);
DISPLAY 0.617021 (2060 4685);
PAINT ORANGE (2060 4685);
FORCEPROP 2 LASTPIN (2050 4625) $PN 121
J 0
(2060 4635);
DISPLAY 0.617021 (2060 4635);
PAINT ORANGE (2060 4635);
FORCEPROP 2 LASTPIN (2050 4575) $PN 122
J 0
(2060 4585);
DISPLAY 0.617021 (2060 4585);
PAINT ORANGE (2060 4585);
FORCEPROP 2 LASTPIN (2050 4525) $PN 110
J 0
(2060 4535);
DISPLAY 0.617021 (2060 4535);
PAINT ORANGE (2060 4535);
FORCEPROP 2 LASTPIN (2050 4475) $PN 111
J 0
(2060 4485);
DISPLAY 0.617021 (2060 4485);
PAINT ORANGE (2060 4485);
FORCEPROP 2 LASTPIN (2050 4425) $PN 99
J 0
(2060 4435);
DISPLAY 0.617021 (2060 4435);
PAINT ORANGE (2060 4435);
FORCEPROP 2 LASTPIN (2050 4375) $PN 100
J 0
(2060 4385);
DISPLAY 0.617021 (2060 4385);
PAINT ORANGE (2060 4385);
FORCEPROP 2 LASTPIN (2050 4325) $PN 40
J 0
(2060 4335);
DISPLAY 0.617021 (2060 4335);
PAINT ORANGE (2060 4335);
FORCEPROP 2 LASTPIN (2050 4275) $PN 41
J 0
(2060 4285);
DISPLAY 0.617021 (2060 4285);
PAINT ORANGE (2060 4285);
FORCEPROP 2 LASTPIN (2050 4225) $PN 29
J 0
(2060 4235);
DISPLAY 0.617021 (2060 4235);
PAINT ORANGE (2060 4235);
FORCEPROP 2 LASTPIN (2050 4175) $PN 30
J 0
(2060 4185);
DISPLAY 0.617021 (2060 4185);
PAINT ORANGE (2060 4185);
FORCEPROP 2 LASTPIN (2050 4125) $PN 18
J 0
(2060 4135);
DISPLAY 0.617021 (2060 4135);
PAINT ORANGE (2060 4135);
FORCEPROP 2 LASTPIN (2050 4075) $PN 19
J 0
(2060 4085);
DISPLAY 0.617021 (2060 4085);
PAINT ORANGE (2060 4085);
FORCEPROP 2 LASTPIN (2050 4025) $PN 7
J 0
(2060 4035);
DISPLAY 0.617021 (2060 4035);
PAINT ORANGE (2060 4035);
FORCEPROP 2 LASTPIN (2050 3975) $PN 8
J 0
(2060 3985);
DISPLAY 0.617021 (2060 3985);
PAINT ORANGE (2060 3985);
FORCEPROP 2 LASTPIN (2050 3925) $PN 197
J 0
(2060 3935);
DISPLAY 0.617021 (2060 3935);
PAINT ORANGE (2060 3935);
FORCEPROP 2 LASTPIN (2050 3875) $PN 196
J 0
(2060 3885);
DISPLAY 0.617021 (2060 3885);
PAINT ORANGE (2060 3885);
FORCEPROP 2 LASTPIN (2050 3825) $PN 278
J 0
(2060 3835);
DISPLAY 0.617021 (2060 3835);
PAINT ORANGE (2060 3835);
FORCEPROP 2 LASTPIN (2050 3775) $PN 277
J 0
(2060 3785);
DISPLAY 0.617021 (2060 3785);
PAINT ORANGE (2060 3785);
FORCEPROP 2 LASTPIN (2050 3725) $PN 267
J 0
(2060 3735);
DISPLAY 0.617021 (2060 3735);
PAINT ORANGE (2060 3735);
FORCEPROP 2 LASTPIN (2050 3675) $PN 266
J 0
(2060 3685);
DISPLAY 0.617021 (2060 3685);
PAINT ORANGE (2060 3685);
FORCEPROP 2 LASTPIN (2050 3625) $PN 256
J 0
(2060 3635);
DISPLAY 0.617021 (2060 3635);
PAINT ORANGE (2060 3635);
FORCEPROP 2 LASTPIN (2050 3575) $PN 255
J 0
(2060 3585);
DISPLAY 0.617021 (2060 3585);
PAINT ORANGE (2060 3585);
FORCEPROP 2 LASTPIN (2050 3525) $PN 245
J 0
(2060 3535);
DISPLAY 0.617021 (2060 3535);
PAINT ORANGE (2060 3535);
FORCEPROP 2 LASTPIN (2050 3475) $PN 244
J 0
(2060 3485);
DISPLAY 0.617021 (2060 3485);
PAINT ORANGE (2060 3485);
FORCEPROP 2 LASTPIN (2050 3425) $PN 186
J 0
(2060 3435);
DISPLAY 0.617021 (2060 3435);
PAINT ORANGE (2060 3435);
FORCEPROP 2 LASTPIN (2050 3375) $PN 185
J 0
(2060 3385);
DISPLAY 0.617021 (2060 3385);
PAINT ORANGE (2060 3385);
FORCEPROP 2 LASTPIN (2050 3325) $PN 175
J 0
(2060 3335);
DISPLAY 0.617021 (2060 3335);
PAINT ORANGE (2060 3335);
FORCEPROP 2 LASTPIN (2050 3275) $PN 174
J 0
(2060 3285);
DISPLAY 0.617021 (2060 3285);
PAINT ORANGE (2060 3285);
FORCEPROP 2 LASTPIN (2050 3225) $PN 164
J 0
(2060 3235);
DISPLAY 0.617021 (2060 3235);
PAINT ORANGE (2060 3235);
FORCEPROP 2 LASTPIN (2050 3175) $PN 163
J 0
(2060 3185);
DISPLAY 0.617021 (2060 3185);
PAINT ORANGE (2060 3185);
FORCEPROP 2 LASTPIN (2050 3125) $PN 153
J 0
(2060 3135);
DISPLAY 0.617021 (2060 3135);
PAINT ORANGE (2060 3135);
FORCEPROP 2 LASTPIN (2050 3075) $PN 152
J 0
(2060 3085);
DISPLAY 0.617021 (2060 3085);
PAINT ORANGE (2060 3085);
FORCEPROP 1 LAST PACK_TYPE PIP
J 0
(1200 5125);
PAINT SKYBLUE (1200 5125);
DISPLAY INVISIBLE (1200 5125);
FORCEPROP 2 LAST BOM_COST MEM
J 0
(1600 3975);
PAINT ORANGE (1600 3975);
DISPLAY INVISIBLE (1600 3975);
FORCEPROP 2 LAST CDS_LIB mstr_sconn
J 0
(1600 3975);
PAINT ORANGE (1600 3975);
DISPLAY INVISIBLE (1600 3975);
FORCEPROP 2 LAST SEC_TYPE PIP
J 0
(1200 5125);
DISPLAY 1.021277 (1200 5125);
PAINT ORANGE (1200 5125);
DISPLAY INVISIBLE (1200 5125);
FORCEPROP 2 LAST SEC 2
J 0
(1200 5125);
DISPLAY 0.680851 (1200 5125);
PAINT MONO (1200 5125);
DISPLAY INVISIBLE (1200 5125);
FORCEPROP 2 LAST CDS_LOCATION J9M1
J 0
(1200 5075);
DISPLAY 0.617021 (1200 5075);
PAINT AQUA (1200 5075);
DISPLAY INVISIBLE (1200 5075);
FORCEPROP 1 LAST PATH I102
J 0
(1600 5025);
PAINT GREEN (1600 5025);
DISPLAY INVISIBLE (1600 5025);
FORCEPROP 2 LAST ROOM DDR4_CH_K
J 0
(1200 5175);
PAINT ORANGE (1200 5175);
DISPLAY INVISIBLE (1200 5175);
FORCEADD OFFPAGE..1
(-2250 4525);
FORCEPROP 2 LAST $XR0 60 
J 0
(-2501 4525);
DISPLAY 0.638298 (-2501 4525);
PAINT MONO (-2501 4525);
FORCEPROP 2 LAST $XR1 83 
J 0
(-2591 4525);
DISPLAY 0.638298 (-2591 4525);
PAINT MONO (-2591 4525);
FORCEPROP 2 LAST CDS_LIB mstr_standard
J 0
(-2250 4525);
DISPLAY 0.787234 (-2250 4525);
PAINT MONO (-2250 4525);
DISPLAY INVISIBLE (-2250 4525);
FORCEPROP 1 LAST OFFPAGE TRUE
J 0
(-1925 4400);
DISPLAY 0.936170 (-1925 4400);
PAINT GREEN (-1925 4400);
DISPLAY INVISIBLE (-1925 4400);
FORCEPROP 1 LAST COMMENT_BODY TRUE
J 0
(-2125 4425);
DISPLAY 0.936170 (-2125 4425);
PAINT GREEN (-2125 4425);
DISPLAY INVISIBLE (-2125 4425);
FORCEPROP 2 LAST PATH I103
J 0
(-2500 4575);
DISPLAY 1.021277 (-2500 4575);
PAINT ORANGE (-2500 4575);
DISPLAY INVISIBLE (-2500 4575);
FORCEADD TAP..6
(-1600 3775);
FORCEPROP 3 LASTPIN (-1550 3775) SIG_NAME M_K_MA<3>
J 0
(-1540 3785);
DISPLAY 0.659574 (-1540 3785);
PAINT MONO (-1540 3785);
DISPLAY INVISIBLE (-1540 3785);
FORCEPROP 1 LASTPIN (-1550 3775) BN 3
J 0
(-1600 3785);
DISPLAY 0.617021 (-1600 3785);
PAINT PINK (-1600 3785);
FORCEPROP 2 LAST CDS_LIB mstr_standard
J 2
(-1600 3775);
DISPLAY 0.787234 (-1600 3775);
PAINT MONO (-1600 3775);
DISPLAY INVISIBLE (-1600 3775);
FORCEPROP 1 LAST BODY_TYPE PLUMBING
J 0
(-1600 3725);
DISPLAY 1.234043 (-1600 3725);
PAINT GREEN (-1600 3725);
DISPLAY INVISIBLE (-1600 3725);
FORCEPROP 1 LAST HDL_TAP TRUE
J 0
(-1275 3650);
DISPLAY 1.234043 (-1275 3650);
PAINT GREEN (-1275 3650);
DISPLAY INVISIBLE (-1275 3650);
FORCEPROP 1 LAST PATH I104
J 0
(-1602 3775);
DISPLAY 0.872340 (-1602 3775);
PAINT GREEN (-1602 3775);
DISPLAY INVISIBLE (-1602 3775);
FORCEADD TAP..6
(-1600 3725);
FORCEPROP 3 LASTPIN (-1550 3725) SIG_NAME M_K_MA<2>
J 0
(-1540 3735);
DISPLAY 0.659574 (-1540 3735);
PAINT MONO (-1540 3735);
DISPLAY INVISIBLE (-1540 3735);
FORCEPROP 1 LASTPIN (-1550 3725) BN 2
J 0
(-1600 3735);
DISPLAY 0.617021 (-1600 3735);
PAINT PINK (-1600 3735);
FORCEPROP 2 LAST CDS_LIB mstr_standard
J 2
(-1600 3725);
DISPLAY 0.787234 (-1600 3725);
PAINT MONO (-1600 3725);
DISPLAY INVISIBLE (-1600 3725);
FORCEPROP 1 LAST BODY_TYPE PLUMBING
J 0
(-1600 3675);
DISPLAY 1.234043 (-1600 3675);
PAINT GREEN (-1600 3675);
DISPLAY INVISIBLE (-1600 3675);
FORCEPROP 1 LAST HDL_TAP TRUE
J 0
(-1275 3600);
DISPLAY 1.234043 (-1275 3600);
PAINT GREEN (-1275 3600);
DISPLAY INVISIBLE (-1275 3600);
FORCEPROP 1 LAST PATH I105
J 0
(-1602 3725);
DISPLAY 0.872340 (-1602 3725);
PAINT GREEN (-1602 3725);
DISPLAY INVISIBLE (-1602 3725);
FORCEADD TAP..6
(-1600 3925);
FORCEPROP 3 LASTPIN (-1550 3925) SIG_NAME M_K_MA<6>
J 0
(-1540 3935);
DISPLAY 0.659574 (-1540 3935);
PAINT MONO (-1540 3935);
DISPLAY INVISIBLE (-1540 3935);
FORCEPROP 1 LASTPIN (-1550 3925) BN 6
J 0
(-1600 3935);
DISPLAY 0.617021 (-1600 3935);
PAINT PINK (-1600 3935);
FORCEPROP 2 LAST CDS_LIB mstr_standard
J 2
(-1600 3925);
DISPLAY 0.787234 (-1600 3925);
PAINT MONO (-1600 3925);
DISPLAY INVISIBLE (-1600 3925);
FORCEPROP 1 LAST BODY_TYPE PLUMBING
J 0
(-1600 3875);
DISPLAY 1.234043 (-1600 3875);
PAINT GREEN (-1600 3875);
DISPLAY INVISIBLE (-1600 3875);
FORCEPROP 1 LAST HDL_TAP TRUE
J 0
(-1275 3800);
DISPLAY 1.234043 (-1275 3800);
PAINT GREEN (-1275 3800);
DISPLAY INVISIBLE (-1275 3800);
FORCEPROP 1 LAST PATH I106
J 0
(-1602 3925);
DISPLAY 0.872340 (-1602 3925);
PAINT GREEN (-1602 3925);
DISPLAY INVISIBLE (-1602 3925);
FORCEADD TAP..6
(-1600 3875);
FORCEPROP 3 LASTPIN (-1550 3875) SIG_NAME M_K_MA<5>
J 0
(-1540 3885);
DISPLAY 0.659574 (-1540 3885);
PAINT MONO (-1540 3885);
DISPLAY INVISIBLE (-1540 3885);
FORCEPROP 1 LASTPIN (-1550 3875) BN 5
J 0
(-1600 3885);
DISPLAY 0.617021 (-1600 3885);
PAINT PINK (-1600 3885);
FORCEPROP 2 LAST CDS_LIB mstr_standard
J 2
(-1600 3875);
DISPLAY 0.787234 (-1600 3875);
PAINT MONO (-1600 3875);
DISPLAY INVISIBLE (-1600 3875);
FORCEPROP 1 LAST BODY_TYPE PLUMBING
J 0
(-1600 3825);
DISPLAY 1.234043 (-1600 3825);
PAINT GREEN (-1600 3825);
DISPLAY INVISIBLE (-1600 3825);
FORCEPROP 1 LAST HDL_TAP TRUE
J 0
(-1275 3750);
DISPLAY 1.234043 (-1275 3750);
PAINT GREEN (-1275 3750);
DISPLAY INVISIBLE (-1275 3750);
FORCEPROP 1 LAST PATH I107
J 0
(-1602 3875);
DISPLAY 0.872340 (-1602 3875);
PAINT GREEN (-1602 3875);
DISPLAY INVISIBLE (-1602 3875);
FORCEADD TAP..6
(-1600 3825);
FORCEPROP 3 LASTPIN (-1550 3825) SIG_NAME M_K_MA<4>
J 0
(-1540 3835);
DISPLAY 0.659574 (-1540 3835);
PAINT MONO (-1540 3835);
DISPLAY INVISIBLE (-1540 3835);
FORCEPROP 1 LASTPIN (-1550 3825) BN 4
J 0
(-1600 3835);
DISPLAY 0.617021 (-1600 3835);
PAINT PINK (-1600 3835);
FORCEPROP 2 LAST CDS_LIB mstr_standard
J 2
(-1600 3825);
DISPLAY 0.787234 (-1600 3825);
PAINT MONO (-1600 3825);
DISPLAY INVISIBLE (-1600 3825);
FORCEPROP 1 LAST BODY_TYPE PLUMBING
J 0
(-1600 3775);
DISPLAY 1.234043 (-1600 3775);
PAINT GREEN (-1600 3775);
DISPLAY INVISIBLE (-1600 3775);
FORCEPROP 1 LAST HDL_TAP TRUE
J 0
(-1275 3700);
DISPLAY 1.234043 (-1275 3700);
PAINT GREEN (-1275 3700);
DISPLAY INVISIBLE (-1275 3700);
FORCEPROP 1 LAST PATH I108
J 0
(-1602 3825);
DISPLAY 0.872340 (-1602 3825);
PAINT GREEN (-1602 3825);
DISPLAY INVISIBLE (-1602 3825);
FORCEADD TAP..6
(-1600 3975);
FORCEPROP 3 LASTPIN (-1550 3975) SIG_NAME M_K_MA<7>
J 0
(-1540 3985);
DISPLAY 0.659574 (-1540 3985);
PAINT MONO (-1540 3985);
DISPLAY INVISIBLE (-1540 3985);
FORCEPROP 1 LASTPIN (-1550 3975) BN 7
J 0
(-1600 3985);
DISPLAY 0.617021 (-1600 3985);
PAINT PINK (-1600 3985);
FORCEPROP 2 LAST CDS_LIB mstr_standard
J 2
(-1600 3975);
DISPLAY 0.787234 (-1600 3975);
PAINT MONO (-1600 3975);
DISPLAY INVISIBLE (-1600 3975);
FORCEPROP 1 LAST BODY_TYPE PLUMBING
J 0
(-1600 3925);
DISPLAY 1.234043 (-1600 3925);
PAINT GREEN (-1600 3925);
DISPLAY INVISIBLE (-1600 3925);
FORCEPROP 1 LAST HDL_TAP TRUE
J 0
(-1275 3850);
DISPLAY 1.234043 (-1275 3850);
PAINT GREEN (-1275 3850);
DISPLAY INVISIBLE (-1275 3850);
FORCEPROP 1 LAST PATH I109
J 0
(-1602 3975);
DISPLAY 0.872340 (-1602 3975);
PAINT GREEN (-1602 3975);
DISPLAY INVISIBLE (-1602 3975);
FORCEADD OFFPAGE..1
(-2250 1025);
FORCEPROP 2 LAST $XR0 89 
J 0
(-2501 1025);
DISPLAY 0.638298 (-2501 1025);
PAINT MONO (-2501 1025);
FORCEPROP 2 LAST $XR1 83 
J 0
(-2591 1025);
DISPLAY 0.638298 (-2591 1025);
PAINT MONO (-2591 1025);
FORCEPROP 2 LAST $XR2 85 
J 0
(-2681 1025);
DISPLAY 0.638298 (-2681 1025);
PAINT MONO (-2681 1025);
FORCEPROP 2 LAST $XR3 86 
J 0
(-2771 1025);
DISPLAY 0.638298 (-2771 1025);
PAINT MONO (-2771 1025);
FORCEPROP 2 LAST $XR4 87 
J 0
(-2861 1025);
DISPLAY 0.638298 (-2861 1025);
PAINT MONO (-2861 1025);
FORCEPROP 2 LAST $XR5 88 
J 0
(-2951 1025);
DISPLAY 0.638298 (-2951 1025);
PAINT MONO (-2951 1025);
FORCEPROP 2 LAST CDS_LIB mstr_standard
J 0
(-2250 1025);
PAINT ORANGE (-2250 1025);
DISPLAY INVISIBLE (-2250 1025);
FORCEPROP 1 LAST OFFPAGE TRUE
J 0
(-1925 900);
DISPLAY 0.936170 (-1925 900);
PAINT GREEN (-1925 900);
DISPLAY INVISIBLE (-1925 900);
FORCEPROP 1 LAST COMMENT_BODY TRUE
J 0
(-2125 925);
DISPLAY 0.936170 (-2125 925);
PAINT GREEN (-2125 925);
DISPLAY INVISIBLE (-2125 925);
FORCEPROP 2 LAST PATH I11
J 0
(-2500 1075);
DISPLAY 1.021277 (-2500 1075);
PAINT ORANGE (-2500 1075);
DISPLAY INVISIBLE (-2500 1075);
FORCEADD TAP..6
(-1600 4025);
FORCEPROP 3 LASTPIN (-1550 4025) SIG_NAME M_K_MA<8>
J 0
(-1540 4035);
DISPLAY 0.659574 (-1540 4035);
PAINT MONO (-1540 4035);
DISPLAY INVISIBLE (-1540 4035);
FORCEPROP 1 LASTPIN (-1550 4025) BN 8
J 0
(-1600 4035);
DISPLAY 0.617021 (-1600 4035);
PAINT PINK (-1600 4035);
FORCEPROP 2 LAST CDS_LIB mstr_standard
J 2
(-1600 4025);
DISPLAY 0.787234 (-1600 4025);
PAINT MONO (-1600 4025);
DISPLAY INVISIBLE (-1600 4025);
FORCEPROP 1 LAST BODY_TYPE PLUMBING
J 0
(-1600 3975);
DISPLAY 1.234043 (-1600 3975);
PAINT GREEN (-1600 3975);
DISPLAY INVISIBLE (-1600 3975);
FORCEPROP 1 LAST HDL_TAP TRUE
J 0
(-1275 3900);
DISPLAY 1.234043 (-1275 3900);
PAINT GREEN (-1275 3900);
DISPLAY INVISIBLE (-1275 3900);
FORCEPROP 1 LAST PATH I110
J 0
(-1602 4025);
DISPLAY 0.872340 (-1602 4025);
PAINT GREEN (-1602 4025);
DISPLAY INVISIBLE (-1602 4025);
FORCEADD TAP..6
(-1600 4075);
FORCEPROP 3 LASTPIN (-1550 4075) SIG_NAME M_K_MA<9>
J 0
(-1540 4085);
DISPLAY 0.659574 (-1540 4085);
PAINT MONO (-1540 4085);
DISPLAY INVISIBLE (-1540 4085);
FORCEPROP 1 LASTPIN (-1550 4075) BN 9
J 0
(-1600 4085);
DISPLAY 0.617021 (-1600 4085);
PAINT PINK (-1600 4085);
FORCEPROP 2 LAST CDS_LIB mstr_standard
J 2
(-1600 4075);
DISPLAY 0.787234 (-1600 4075);
PAINT MONO (-1600 4075);
DISPLAY INVISIBLE (-1600 4075);
FORCEPROP 1 LAST BODY_TYPE PLUMBING
J 0
(-1600 4025);
DISPLAY 1.234043 (-1600 4025);
PAINT GREEN (-1600 4025);
DISPLAY INVISIBLE (-1600 4025);
FORCEPROP 1 LAST HDL_TAP TRUE
J 0
(-1275 3950);
DISPLAY 1.234043 (-1275 3950);
PAINT GREEN (-1275 3950);
DISPLAY INVISIBLE (-1275 3950);
FORCEPROP 1 LAST PATH I111
J 0
(-1602 4075);
DISPLAY 0.872340 (-1602 4075);
PAINT GREEN (-1602 4075);
DISPLAY INVISIBLE (-1602 4075);
FORCEADD TAP..6
(-1600 4175);
FORCEPROP 3 LASTPIN (-1550 4175) SIG_NAME M_K_MA<11>
J 0
(-1540 4185);
DISPLAY 0.659574 (-1540 4185);
PAINT MONO (-1540 4185);
DISPLAY INVISIBLE (-1540 4185);
FORCEPROP 1 LASTPIN (-1550 4175) BN 11
J 0
(-1600 4185);
DISPLAY 0.617021 (-1600 4185);
PAINT PINK (-1600 4185);
FORCEPROP 2 LAST CDS_LIB mstr_standard
J 2
(-1600 4175);
DISPLAY 0.787234 (-1600 4175);
PAINT MONO (-1600 4175);
DISPLAY INVISIBLE (-1600 4175);
FORCEPROP 1 LAST BODY_TYPE PLUMBING
J 0
(-1600 4125);
DISPLAY 1.234043 (-1600 4125);
PAINT GREEN (-1600 4125);
DISPLAY INVISIBLE (-1600 4125);
FORCEPROP 1 LAST HDL_TAP TRUE
J 0
(-1275 4050);
DISPLAY 1.234043 (-1275 4050);
PAINT GREEN (-1275 4050);
DISPLAY INVISIBLE (-1275 4050);
FORCEPROP 1 LAST PATH I112
J 0
(-1602 4175);
DISPLAY 0.872340 (-1602 4175);
PAINT GREEN (-1602 4175);
DISPLAY INVISIBLE (-1602 4175);
FORCEADD TAP..6
(-1600 4125);
FORCEPROP 3 LASTPIN (-1550 4125) SIG_NAME M_K_MA<10>
J 0
(-1540 4135);
DISPLAY 0.659574 (-1540 4135);
PAINT MONO (-1540 4135);
DISPLAY INVISIBLE (-1540 4135);
FORCEPROP 1 LASTPIN (-1550 4125) BN 10
J 0
(-1600 4135);
DISPLAY 0.617021 (-1600 4135);
PAINT PINK (-1600 4135);
FORCEPROP 2 LAST CDS_LIB mstr_standard
J 2
(-1600 4125);
DISPLAY 0.787234 (-1600 4125);
PAINT MONO (-1600 4125);
DISPLAY INVISIBLE (-1600 4125);
FORCEPROP 1 LAST BODY_TYPE PLUMBING
J 0
(-1600 4075);
DISPLAY 1.234043 (-1600 4075);
PAINT GREEN (-1600 4075);
DISPLAY INVISIBLE (-1600 4075);
FORCEPROP 1 LAST HDL_TAP TRUE
J 0
(-1275 4000);
DISPLAY 1.234043 (-1275 4000);
PAINT GREEN (-1275 4000);
DISPLAY INVISIBLE (-1275 4000);
FORCEPROP 1 LAST PATH I113
J 0
(-1602 4125);
DISPLAY 0.872340 (-1602 4125);
PAINT GREEN (-1602 4125);
DISPLAY INVISIBLE (-1602 4125);
FORCEADD TAP..6
(-1600 4225);
FORCEPROP 3 LASTPIN (-1550 4225) SIG_NAME M_K_MA<12>
J 0
(-1540 4235);
DISPLAY 0.659574 (-1540 4235);
PAINT MONO (-1540 4235);
DISPLAY INVISIBLE (-1540 4235);
FORCEPROP 1 LASTPIN (-1550 4225) BN 12
J 0
(-1600 4235);
DISPLAY 0.617021 (-1600 4235);
PAINT PINK (-1600 4235);
FORCEPROP 2 LAST CDS_LIB mstr_standard
J 2
(-1600 4225);
DISPLAY 0.787234 (-1600 4225);
PAINT MONO (-1600 4225);
DISPLAY INVISIBLE (-1600 4225);
FORCEPROP 1 LAST BODY_TYPE PLUMBING
J 0
(-1600 4175);
DISPLAY 1.234043 (-1600 4175);
PAINT GREEN (-1600 4175);
DISPLAY INVISIBLE (-1600 4175);
FORCEPROP 1 LAST HDL_TAP TRUE
J 0
(-1275 4100);
DISPLAY 1.234043 (-1275 4100);
PAINT GREEN (-1275 4100);
DISPLAY INVISIBLE (-1275 4100);
FORCEPROP 1 LAST PATH I114
J 0
(-1602 4225);
DISPLAY 0.872340 (-1602 4225);
PAINT GREEN (-1602 4225);
DISPLAY INVISIBLE (-1602 4225);
FORCEADD TAP..6
(-1600 4275);
FORCEPROP 3 LASTPIN (-1550 4275) SIG_NAME M_K_MA<13>
J 0
(-1540 4285);
DISPLAY 0.659574 (-1540 4285);
PAINT MONO (-1540 4285);
DISPLAY INVISIBLE (-1540 4285);
FORCEPROP 1 LASTPIN (-1550 4275) BN 13
J 0
(-1600 4285);
DISPLAY 0.617021 (-1600 4285);
PAINT PINK (-1600 4285);
FORCEPROP 2 LAST CDS_LIB mstr_standard
J 2
(-1600 4275);
DISPLAY 0.787234 (-1600 4275);
PAINT MONO (-1600 4275);
DISPLAY INVISIBLE (-1600 4275);
FORCEPROP 1 LAST BODY_TYPE PLUMBING
J 0
(-1600 4225);
DISPLAY 1.234043 (-1600 4225);
PAINT GREEN (-1600 4225);
DISPLAY INVISIBLE (-1600 4225);
FORCEPROP 1 LAST HDL_TAP TRUE
J 0
(-1275 4150);
DISPLAY 1.234043 (-1275 4150);
PAINT GREEN (-1275 4150);
DISPLAY INVISIBLE (-1275 4150);
FORCEPROP 1 LAST PATH I115
J 0
(-1602 4275);
DISPLAY 0.872340 (-1602 4275);
PAINT GREEN (-1602 4275);
DISPLAY INVISIBLE (-1602 4275);
FORCEADD TAP..6
(-1600 4325);
FORCEPROP 3 LASTPIN (-1550 4325) SIG_NAME M_K_MA<14>
J 0
(-1540 4335);
DISPLAY 0.659574 (-1540 4335);
PAINT MONO (-1540 4335);
DISPLAY INVISIBLE (-1540 4335);
FORCEPROP 1 LASTPIN (-1550 4325) BN 14
J 0
(-1600 4335);
DISPLAY 0.617021 (-1600 4335);
PAINT PINK (-1600 4335);
FORCEPROP 2 LAST CDS_LIB mstr_standard
J 2
(-1600 4325);
DISPLAY 0.787234 (-1600 4325);
PAINT MONO (-1600 4325);
DISPLAY INVISIBLE (-1600 4325);
FORCEPROP 1 LAST BODY_TYPE PLUMBING
J 0
(-1600 4275);
DISPLAY 1.234043 (-1600 4275);
PAINT GREEN (-1600 4275);
DISPLAY INVISIBLE (-1600 4275);
FORCEPROP 1 LAST HDL_TAP TRUE
J 0
(-1275 4200);
DISPLAY 1.234043 (-1275 4200);
PAINT GREEN (-1275 4200);
DISPLAY INVISIBLE (-1275 4200);
FORCEPROP 1 LAST PATH I116
J 0
(-1602 4325);
DISPLAY 0.872340 (-1602 4325);
PAINT GREEN (-1602 4325);
DISPLAY INVISIBLE (-1602 4325);
FORCEADD TAP..6
(-1600 4425);
FORCEPROP 3 LASTPIN (-1550 4425) SIG_NAME M_K_MA<16>
J 0
(-1540 4435);
DISPLAY 0.659574 (-1540 4435);
PAINT MONO (-1540 4435);
DISPLAY INVISIBLE (-1540 4435);
FORCEPROP 1 LASTPIN (-1550 4425) BN 16
J 0
(-1600 4435);
DISPLAY 0.617021 (-1600 4435);
PAINT PINK (-1600 4435);
FORCEPROP 2 LAST CDS_LIB mstr_standard
J 2
(-1600 4425);
DISPLAY 0.787234 (-1600 4425);
PAINT MONO (-1600 4425);
DISPLAY INVISIBLE (-1600 4425);
FORCEPROP 1 LAST BODY_TYPE PLUMBING
J 0
(-1600 4375);
DISPLAY 1.234043 (-1600 4375);
PAINT GREEN (-1600 4375);
DISPLAY INVISIBLE (-1600 4375);
FORCEPROP 1 LAST HDL_TAP TRUE
J 0
(-1275 4300);
DISPLAY 1.234043 (-1275 4300);
PAINT GREEN (-1275 4300);
DISPLAY INVISIBLE (-1275 4300);
FORCEPROP 1 LAST PATH I117
J 0
(-1602 4425);
DISPLAY 0.872340 (-1602 4425);
PAINT GREEN (-1602 4425);
DISPLAY INVISIBLE (-1602 4425);
FORCEADD TAP..6
(-1600 4375);
FORCEPROP 3 LASTPIN (-1550 4375) SIG_NAME M_K_MA<15>
J 0
(-1540 4385);
DISPLAY 0.659574 (-1540 4385);
PAINT MONO (-1540 4385);
DISPLAY INVISIBLE (-1540 4385);
FORCEPROP 1 LASTPIN (-1550 4375) BN 15
J 0
(-1600 4385);
DISPLAY 0.617021 (-1600 4385);
PAINT PINK (-1600 4385);
FORCEPROP 2 LAST CDS_LIB mstr_standard
J 2
(-1600 4375);
DISPLAY 0.787234 (-1600 4375);
PAINT MONO (-1600 4375);
DISPLAY INVISIBLE (-1600 4375);
FORCEPROP 1 LAST BODY_TYPE PLUMBING
J 0
(-1600 4325);
DISPLAY 1.234043 (-1600 4325);
PAINT GREEN (-1600 4325);
DISPLAY INVISIBLE (-1600 4325);
FORCEPROP 1 LAST HDL_TAP TRUE
J 0
(-1275 4250);
DISPLAY 1.234043 (-1275 4250);
PAINT GREEN (-1275 4250);
DISPLAY INVISIBLE (-1275 4250);
FORCEPROP 1 LAST PATH I118
J 0
(-1602 4375);
DISPLAY 0.872340 (-1602 4375);
PAINT GREEN (-1602 4375);
DISPLAY INVISIBLE (-1602 4375);
FORCEADD TAP..6
(-1600 4475);
FORCEPROP 3 LASTPIN (-1550 4475) SIG_NAME M_K_MA<17>
J 0
(-1540 4485);
DISPLAY 0.659574 (-1540 4485);
PAINT MONO (-1540 4485);
DISPLAY INVISIBLE (-1540 4485);
FORCEPROP 1 LASTPIN (-1550 4475) BN 17
J 0
(-1600 4485);
DISPLAY 0.617021 (-1600 4485);
PAINT PINK (-1600 4485);
FORCEPROP 2 LAST CDS_LIB mstr_standard
J 0
(-1600 4475);
DISPLAY 0.787234 (-1600 4475);
PAINT MONO (-1600 4475);
DISPLAY INVISIBLE (-1600 4475);
FORCEPROP 1 LAST BODY_TYPE PLUMBING
J 0
(-1600 4425);
DISPLAY 1.234043 (-1600 4425);
PAINT GREEN (-1600 4425);
DISPLAY INVISIBLE (-1600 4425);
FORCEPROP 1 LAST HDL_TAP TRUE
J 0
(-1275 4350);
DISPLAY 1.234043 (-1275 4350);
PAINT GREEN (-1275 4350);
DISPLAY INVISIBLE (-1275 4350);
FORCEPROP 1 LAST PATH I119
J 0
(-1602 4475);
DISPLAY 0.872340 (-1602 4475);
PAINT GREEN (-1602 4475);
DISPLAY INVISIBLE (-1602 4475);
FORCEADD OFFPAGE..1
(-2200 1425);
FORCEPROP 2 LAST $XR0 99 
J 0
(-2451 1425);
DISPLAY 0.638298 (-2451 1425);
PAINT MONO (-2451 1425);
FORCEPROP 2 LAST $XR1 83 
J 0
(-2541 1425);
DISPLAY 0.638298 (-2541 1425);
PAINT MONO (-2541 1425);
FORCEPROP 2 LAST $XR2 85 
J 0
(-2631 1425);
DISPLAY 0.638298 (-2631 1425);
PAINT MONO (-2631 1425);
FORCEPROP 2 LAST $XR3 86 
J 0
(-2721 1425);
DISPLAY 0.638298 (-2721 1425);
PAINT MONO (-2721 1425);
FORCEPROP 2 LAST $XR4 87 
J 0
(-2811 1425);
DISPLAY 0.638298 (-2811 1425);
PAINT MONO (-2811 1425);
FORCEPROP 2 LAST $XR5 88 
J 0
(-2901 1425);
DISPLAY 0.638298 (-2901 1425);
PAINT MONO (-2901 1425);
FORCEPROP 2 LAST CDS_LIB mstr_standard
J 0
(-2200 1425);
DISPLAY 0.787234 (-2200 1425);
PAINT MONO (-2200 1425);
DISPLAY INVISIBLE (-2200 1425);
FORCEPROP 1 LAST OFFPAGE TRUE
J 0
(-1875 1300);
DISPLAY 0.936170 (-1875 1300);
PAINT GREEN (-1875 1300);
DISPLAY INVISIBLE (-1875 1300);
FORCEPROP 1 LAST COMMENT_BODY TRUE
J 0
(-2075 1325);
DISPLAY 0.936170 (-2075 1325);
PAINT GREEN (-2075 1325);
DISPLAY INVISIBLE (-2075 1325);
FORCEPROP 2 LAST PATH I12
J 0
(-2450 1475);
DISPLAY 1.021277 (-2450 1475);
PAINT ORANGE (-2450 1475);
DISPLAY INVISIBLE (-2450 1475);
FORCEADD TAP..6
R 2
(-100 3825);
FORCEPROP 3 LASTPIN (-150 3825) SIG_NAME M_K_DQ<50>
J 0
(-140 3835);
DISPLAY 0.659574 (-140 3835);
PAINT MONO (-140 3835);
DISPLAY INVISIBLE (-140 3835);
FORCEPROP 1 LASTPIN (-150 3825) BN 50
J 2
(-100 3835);
DISPLAY 0.617021 (-100 3835);
PAINT PINK (-100 3835);
FORCEPROP 2 LAST CDS_LIB mstr_standard
J 2
(-100 3825);
DISPLAY 0.787234 (-100 3825);
PAINT MONO (-100 3825);
DISPLAY INVISIBLE (-100 3825);
FORCEPROP 1 LAST BODY_TYPE PLUMBING
J 2
(-100 3775);
DISPLAY 1.234043 (-100 3775);
PAINT GREEN (-100 3775);
DISPLAY INVISIBLE (-100 3775);
FORCEPROP 1 LAST HDL_TAP TRUE
J 2
(-425 3700);
DISPLAY 1.234043 (-425 3700);
PAINT GREEN (-425 3700);
DISPLAY INVISIBLE (-425 3700);
FORCEPROP 1 LAST PATH I120
J 2
(-98 3825);
DISPLAY 0.872340 (-98 3825);
PAINT GREEN (-98 3825);
DISPLAY INVISIBLE (-98 3825);
FORCEADD TAP..6
R 2
(-100 3725);
FORCEPROP 3 LASTPIN (-150 3725) SIG_NAME M_K_DQ<48>
J 0
(-140 3735);
DISPLAY 0.659574 (-140 3735);
PAINT MONO (-140 3735);
DISPLAY INVISIBLE (-140 3735);
FORCEPROP 1 LASTPIN (-150 3725) BN 48
J 2
(-100 3735);
DISPLAY 0.617021 (-100 3735);
PAINT PINK (-100 3735);
FORCEPROP 2 LAST CDS_LIB mstr_standard
J 2
(-100 3725);
DISPLAY 0.787234 (-100 3725);
PAINT MONO (-100 3725);
DISPLAY INVISIBLE (-100 3725);
FORCEPROP 1 LAST BODY_TYPE PLUMBING
J 2
(-100 3675);
DISPLAY 1.234043 (-100 3675);
PAINT GREEN (-100 3675);
DISPLAY INVISIBLE (-100 3675);
FORCEPROP 1 LAST HDL_TAP TRUE
J 2
(-425 3600);
DISPLAY 1.234043 (-425 3600);
PAINT GREEN (-425 3600);
DISPLAY INVISIBLE (-425 3600);
FORCEPROP 1 LAST PATH I121
J 2
(-98 3725);
DISPLAY 0.872340 (-98 3725);
PAINT GREEN (-98 3725);
DISPLAY INVISIBLE (-98 3725);
FORCEADD TAP..6
R 2
(-100 3775);
FORCEPROP 3 LASTPIN (-150 3775) SIG_NAME M_K_DQ<49>
J 0
(-140 3785);
DISPLAY 0.659574 (-140 3785);
PAINT MONO (-140 3785);
DISPLAY INVISIBLE (-140 3785);
FORCEPROP 1 LASTPIN (-150 3775) BN 49
J 2
(-100 3785);
DISPLAY 0.617021 (-100 3785);
PAINT PINK (-100 3785);
FORCEPROP 2 LAST CDS_LIB mstr_standard
J 2
(-100 3775);
DISPLAY 0.787234 (-100 3775);
PAINT MONO (-100 3775);
DISPLAY INVISIBLE (-100 3775);
FORCEPROP 1 LAST BODY_TYPE PLUMBING
J 2
(-100 3725);
DISPLAY 1.234043 (-100 3725);
PAINT GREEN (-100 3725);
DISPLAY INVISIBLE (-100 3725);
FORCEPROP 1 LAST HDL_TAP TRUE
J 2
(-425 3650);
DISPLAY 1.234043 (-425 3650);
PAINT GREEN (-425 3650);
DISPLAY INVISIBLE (-425 3650);
FORCEPROP 1 LAST PATH I122
J 2
(-98 3775);
DISPLAY 0.872340 (-98 3775);
PAINT GREEN (-98 3775);
DISPLAY INVISIBLE (-98 3775);
FORCEADD TAP..6
R 2
(-100 3975);
FORCEPROP 3 LASTPIN (-150 3975) SIG_NAME M_K_DQ<53>
J 0
(-140 3985);
DISPLAY 0.659574 (-140 3985);
PAINT MONO (-140 3985);
DISPLAY INVISIBLE (-140 3985);
FORCEPROP 1 LASTPIN (-150 3975) BN 53
J 2
(-100 3985);
DISPLAY 0.617021 (-100 3985);
PAINT PINK (-100 3985);
FORCEPROP 2 LAST CDS_LIB mstr_standard
J 2
(-100 3975);
DISPLAY 0.787234 (-100 3975);
PAINT MONO (-100 3975);
DISPLAY INVISIBLE (-100 3975);
FORCEPROP 1 LAST BODY_TYPE PLUMBING
J 2
(-100 3925);
DISPLAY 1.234043 (-100 3925);
PAINT GREEN (-100 3925);
DISPLAY INVISIBLE (-100 3925);
FORCEPROP 1 LAST HDL_TAP TRUE
J 2
(-425 3850);
DISPLAY 1.234043 (-425 3850);
PAINT GREEN (-425 3850);
DISPLAY INVISIBLE (-425 3850);
FORCEPROP 1 LAST PATH I123
J 2
(-98 3975);
DISPLAY 0.872340 (-98 3975);
PAINT GREEN (-98 3975);
DISPLAY INVISIBLE (-98 3975);
FORCEADD TAP..6
R 2
(-100 3925);
FORCEPROP 3 LASTPIN (-150 3925) SIG_NAME M_K_DQ<52>
J 0
(-140 3935);
DISPLAY 0.659574 (-140 3935);
PAINT MONO (-140 3935);
DISPLAY INVISIBLE (-140 3935);
FORCEPROP 1 LASTPIN (-150 3925) BN 52
J 2
(-100 3935);
DISPLAY 0.617021 (-100 3935);
PAINT PINK (-100 3935);
FORCEPROP 2 LAST CDS_LIB mstr_standard
J 2
(-100 3925);
DISPLAY 0.787234 (-100 3925);
PAINT MONO (-100 3925);
DISPLAY INVISIBLE (-100 3925);
FORCEPROP 1 LAST BODY_TYPE PLUMBING
J 2
(-100 3875);
DISPLAY 1.234043 (-100 3875);
PAINT GREEN (-100 3875);
DISPLAY INVISIBLE (-100 3875);
FORCEPROP 1 LAST HDL_TAP TRUE
J 2
(-425 3800);
DISPLAY 1.234043 (-425 3800);
PAINT GREEN (-425 3800);
DISPLAY INVISIBLE (-425 3800);
FORCEPROP 1 LAST PATH I124
J 2
(-98 3925);
DISPLAY 0.872340 (-98 3925);
PAINT GREEN (-98 3925);
DISPLAY INVISIBLE (-98 3925);
FORCEADD TAP..6
R 2
(-100 3875);
FORCEPROP 3 LASTPIN (-150 3875) SIG_NAME M_K_DQ<51>
J 0
(-140 3885);
DISPLAY 0.659574 (-140 3885);
PAINT MONO (-140 3885);
DISPLAY INVISIBLE (-140 3885);
FORCEPROP 1 LASTPIN (-150 3875) BN 51
J 2
(-100 3885);
DISPLAY 0.617021 (-100 3885);
PAINT PINK (-100 3885);
FORCEPROP 2 LAST CDS_LIB mstr_standard
J 2
(-100 3875);
DISPLAY 0.787234 (-100 3875);
PAINT MONO (-100 3875);
DISPLAY INVISIBLE (-100 3875);
FORCEPROP 1 LAST BODY_TYPE PLUMBING
J 2
(-100 3825);
DISPLAY 1.234043 (-100 3825);
PAINT GREEN (-100 3825);
DISPLAY INVISIBLE (-100 3825);
FORCEPROP 1 LAST HDL_TAP TRUE
J 2
(-425 3750);
DISPLAY 1.234043 (-425 3750);
PAINT GREEN (-425 3750);
DISPLAY INVISIBLE (-425 3750);
FORCEPROP 1 LAST PATH I125
J 2
(-98 3875);
DISPLAY 0.872340 (-98 3875);
PAINT GREEN (-98 3875);
DISPLAY INVISIBLE (-98 3875);
FORCEADD TAP..6
R 2
(-100 4075);
FORCEPROP 3 LASTPIN (-150 4075) SIG_NAME M_K_DQ<55>
J 0
(-140 4085);
DISPLAY 0.659574 (-140 4085);
PAINT MONO (-140 4085);
DISPLAY INVISIBLE (-140 4085);
FORCEPROP 1 LASTPIN (-150 4075) BN 55
J 2
(-100 4085);
DISPLAY 0.617021 (-100 4085);
PAINT PINK (-100 4085);
FORCEPROP 2 LAST CDS_LIB mstr_standard
J 2
(-100 4075);
DISPLAY 0.787234 (-100 4075);
PAINT MONO (-100 4075);
DISPLAY INVISIBLE (-100 4075);
FORCEPROP 1 LAST BODY_TYPE PLUMBING
J 2
(-100 4025);
DISPLAY 1.234043 (-100 4025);
PAINT GREEN (-100 4025);
DISPLAY INVISIBLE (-100 4025);
FORCEPROP 1 LAST HDL_TAP TRUE
J 2
(-425 3950);
DISPLAY 1.234043 (-425 3950);
PAINT GREEN (-425 3950);
DISPLAY INVISIBLE (-425 3950);
FORCEPROP 1 LAST PATH I126
J 2
(-98 4075);
DISPLAY 0.872340 (-98 4075);
PAINT GREEN (-98 4075);
DISPLAY INVISIBLE (-98 4075);
FORCEADD TAP..6
R 2
(-100 4025);
FORCEPROP 3 LASTPIN (-150 4025) SIG_NAME M_K_DQ<54>
J 0
(-140 4035);
DISPLAY 0.659574 (-140 4035);
PAINT MONO (-140 4035);
DISPLAY INVISIBLE (-140 4035);
FORCEPROP 1 LASTPIN (-150 4025) BN 54
J 2
(-100 4035);
DISPLAY 0.617021 (-100 4035);
PAINT PINK (-100 4035);
FORCEPROP 2 LAST CDS_LIB mstr_standard
J 2
(-100 4025);
DISPLAY 0.787234 (-100 4025);
PAINT MONO (-100 4025);
DISPLAY INVISIBLE (-100 4025);
FORCEPROP 1 LAST BODY_TYPE PLUMBING
J 2
(-100 3975);
DISPLAY 1.234043 (-100 3975);
PAINT GREEN (-100 3975);
DISPLAY INVISIBLE (-100 3975);
FORCEPROP 1 LAST HDL_TAP TRUE
J 2
(-425 3900);
DISPLAY 1.234043 (-425 3900);
PAINT GREEN (-425 3900);
DISPLAY INVISIBLE (-425 3900);
FORCEPROP 1 LAST PATH I127
J 2
(-98 4025);
DISPLAY 0.872340 (-98 4025);
PAINT GREEN (-98 4025);
DISPLAY INVISIBLE (-98 4025);
FORCEADD TAP..6
R 2
(-100 4175);
FORCEPROP 3 LASTPIN (-150 4175) SIG_NAME M_K_DQ<57>
J 0
(-140 4185);
DISPLAY 0.659574 (-140 4185);
PAINT MONO (-140 4185);
DISPLAY INVISIBLE (-140 4185);
FORCEPROP 1 LASTPIN (-150 4175) BN 57
J 2
(-100 4185);
DISPLAY 0.617021 (-100 4185);
PAINT PINK (-100 4185);
FORCEPROP 2 LAST CDS_LIB mstr_standard
J 2
(-100 4175);
DISPLAY 0.787234 (-100 4175);
PAINT MONO (-100 4175);
DISPLAY INVISIBLE (-100 4175);
FORCEPROP 1 LAST BODY_TYPE PLUMBING
J 2
(-100 4125);
DISPLAY 1.234043 (-100 4125);
PAINT GREEN (-100 4125);
DISPLAY INVISIBLE (-100 4125);
FORCEPROP 1 LAST HDL_TAP TRUE
J 2
(-425 4050);
DISPLAY 1.234043 (-425 4050);
PAINT GREEN (-425 4050);
DISPLAY INVISIBLE (-425 4050);
FORCEPROP 1 LAST PATH I128
J 2
(-98 4175);
DISPLAY 0.872340 (-98 4175);
PAINT GREEN (-98 4175);
DISPLAY INVISIBLE (-98 4175);
FORCEADD TAP..6
R 2
(-100 4225);
FORCEPROP 3 LASTPIN (-150 4225) SIG_NAME M_K_DQ<58>
J 0
(-140 4235);
DISPLAY 0.659574 (-140 4235);
PAINT MONO (-140 4235);
DISPLAY INVISIBLE (-140 4235);
FORCEPROP 1 LASTPIN (-150 4225) BN 58
J 2
(-100 4235);
DISPLAY 0.617021 (-100 4235);
PAINT PINK (-100 4235);
FORCEPROP 2 LAST CDS_LIB mstr_standard
J 2
(-100 4225);
DISPLAY 0.787234 (-100 4225);
PAINT MONO (-100 4225);
DISPLAY INVISIBLE (-100 4225);
FORCEPROP 1 LAST BODY_TYPE PLUMBING
J 2
(-100 4175);
DISPLAY 1.234043 (-100 4175);
PAINT GREEN (-100 4175);
DISPLAY INVISIBLE (-100 4175);
FORCEPROP 1 LAST HDL_TAP TRUE
J 2
(-425 4100);
DISPLAY 1.234043 (-425 4100);
PAINT GREEN (-425 4100);
DISPLAY INVISIBLE (-425 4100);
FORCEPROP 1 LAST PATH I129
J 2
(-98 4225);
DISPLAY 0.872340 (-98 4225);
PAINT GREEN (-98 4225);
DISPLAY INVISIBLE (-98 4225);
FORCEADD OFFPAGE..6
(-2200 1475);
FORCEPROP 2 LAST $XR0 83 
J 0
(-2449 1475);
DISPLAY 0.638298 (-2449 1475);
PAINT MONO (-2449 1475);
FORCEPROP 2 LAST $XR1 85 
J 0
(-2539 1475);
DISPLAY 0.638298 (-2539 1475);
PAINT MONO (-2539 1475);
FORCEPROP 2 LAST $XR2 86 
J 0
(-2629 1475);
DISPLAY 0.638298 (-2629 1475);
PAINT MONO (-2629 1475);
FORCEPROP 2 LAST $XR3 87 
J 0
(-2719 1475);
DISPLAY 0.638298 (-2719 1475);
PAINT MONO (-2719 1475);
FORCEPROP 2 LAST $XR4 88 
J 0
(-2809 1475);
DISPLAY 0.638298 (-2809 1475);
PAINT MONO (-2809 1475);
FORCEPROP 2 LAST $XR5 99 
J 0
(-2899 1475);
DISPLAY 0.638298 (-2899 1475);
PAINT MONO (-2899 1475);
FORCEPROP 2 LASTPIN (-2150 1475) SIG_NAME SMB_DDR_KLM_VPP_SDA
J 0
(-2110 1485);
DISPLAY 0.617021 (-2110 1485);
PAINT ORANGE (-2110 1485);
FORCEPROP 2 LAST CDS_LIB mstr_standard
J 0
(-2200 1475);
DISPLAY 0.787234 (-2200 1475);
PAINT MONO (-2200 1475);
DISPLAY INVISIBLE (-2200 1475);
FORCEPROP 1 LAST OFFPAGE TRUE
J 0
(-1875 1350);
DISPLAY 0.936170 (-1875 1350);
PAINT GREEN (-1875 1350);
DISPLAY INVISIBLE (-1875 1350);
FORCEPROP 1 LAST COMMENT_BODY TRUE
J 0
(-2100 1400);
DISPLAY 0.936170 (-2100 1400);
PAINT GREEN (-2100 1400);
DISPLAY INVISIBLE (-2100 1400);
FORCEPROP 2 LAST PATH I13
J 0
(-2425 1525);
DISPLAY 1.021277 (-2425 1525);
PAINT ORANGE (-2425 1525);
DISPLAY INVISIBLE (-2425 1525);
FORCEADD TAP..6
R 2
(-100 4125);
FORCEPROP 3 LASTPIN (-150 4125) SIG_NAME M_K_DQ<56>
J 0
(-140 4135);
DISPLAY 0.659574 (-140 4135);
PAINT MONO (-140 4135);
DISPLAY INVISIBLE (-140 4135);
FORCEPROP 1 LASTPIN (-150 4125) BN 56
J 2
(-100 4135);
DISPLAY 0.617021 (-100 4135);
PAINT PINK (-100 4135);
FORCEPROP 2 LAST CDS_LIB mstr_standard
J 2
(-100 4125);
DISPLAY 0.787234 (-100 4125);
PAINT MONO (-100 4125);
DISPLAY INVISIBLE (-100 4125);
FORCEPROP 1 LAST BODY_TYPE PLUMBING
J 2
(-100 4075);
DISPLAY 1.234043 (-100 4075);
PAINT GREEN (-100 4075);
DISPLAY INVISIBLE (-100 4075);
FORCEPROP 1 LAST HDL_TAP TRUE
J 2
(-425 4000);
DISPLAY 1.234043 (-425 4000);
PAINT GREEN (-425 4000);
DISPLAY INVISIBLE (-425 4000);
FORCEPROP 1 LAST PATH I130
J 2
(-98 4125);
DISPLAY 0.872340 (-98 4125);
PAINT GREEN (-98 4125);
DISPLAY INVISIBLE (-98 4125);
FORCEADD TAP..6
R 2
(-100 4275);
FORCEPROP 3 LASTPIN (-150 4275) SIG_NAME M_K_DQ<59>
J 0
(-140 4285);
DISPLAY 0.659574 (-140 4285);
PAINT MONO (-140 4285);
DISPLAY INVISIBLE (-140 4285);
FORCEPROP 1 LASTPIN (-150 4275) BN 59
J 2
(-100 4285);
DISPLAY 0.617021 (-100 4285);
PAINT PINK (-100 4285);
FORCEPROP 2 LAST CDS_LIB mstr_standard
J 2
(-100 4275);
DISPLAY 0.787234 (-100 4275);
PAINT MONO (-100 4275);
DISPLAY INVISIBLE (-100 4275);
FORCEPROP 1 LAST BODY_TYPE PLUMBING
J 2
(-100 4225);
DISPLAY 1.234043 (-100 4225);
PAINT GREEN (-100 4225);
DISPLAY INVISIBLE (-100 4225);
FORCEPROP 1 LAST HDL_TAP TRUE
J 2
(-425 4150);
DISPLAY 1.234043 (-425 4150);
PAINT GREEN (-425 4150);
DISPLAY INVISIBLE (-425 4150);
FORCEPROP 1 LAST PATH I131
J 2
(-98 4275);
DISPLAY 0.872340 (-98 4275);
PAINT GREEN (-98 4275);
DISPLAY INVISIBLE (-98 4275);
FORCEADD TAP..6
R 2
(-100 4325);
FORCEPROP 3 LASTPIN (-150 4325) SIG_NAME M_K_DQ<60>
J 0
(-140 4335);
DISPLAY 0.659574 (-140 4335);
PAINT MONO (-140 4335);
DISPLAY INVISIBLE (-140 4335);
FORCEPROP 1 LASTPIN (-150 4325) BN 60
J 2
(-100 4335);
DISPLAY 0.617021 (-100 4335);
PAINT PINK (-100 4335);
FORCEPROP 2 LAST CDS_LIB mstr_standard
J 2
(-100 4325);
DISPLAY 0.787234 (-100 4325);
PAINT MONO (-100 4325);
DISPLAY INVISIBLE (-100 4325);
FORCEPROP 1 LAST BODY_TYPE PLUMBING
J 2
(-100 4275);
DISPLAY 1.234043 (-100 4275);
PAINT GREEN (-100 4275);
DISPLAY INVISIBLE (-100 4275);
FORCEPROP 1 LAST HDL_TAP TRUE
J 2
(-425 4200);
DISPLAY 1.234043 (-425 4200);
PAINT GREEN (-425 4200);
DISPLAY INVISIBLE (-425 4200);
FORCEPROP 1 LAST PATH I132
J 2
(-98 4325);
DISPLAY 0.872340 (-98 4325);
PAINT GREEN (-98 4325);
DISPLAY INVISIBLE (-98 4325);
FORCEADD TAP..6
R 2
(-100 4475);
FORCEPROP 3 LASTPIN (-150 4475) SIG_NAME M_K_DQ<63>
J 0
(-140 4485);
DISPLAY 0.659574 (-140 4485);
PAINT MONO (-140 4485);
DISPLAY INVISIBLE (-140 4485);
FORCEPROP 1 LASTPIN (-150 4475) BN 63
J 2
(-100 4485);
DISPLAY 0.617021 (-100 4485);
PAINT PINK (-100 4485);
FORCEPROP 2 LAST CDS_LIB mstr_standard
J 2
(-100 4475);
DISPLAY 0.787234 (-100 4475);
PAINT MONO (-100 4475);
DISPLAY INVISIBLE (-100 4475);
FORCEPROP 1 LAST BODY_TYPE PLUMBING
J 2
(-100 4425);
DISPLAY 1.234043 (-100 4425);
PAINT GREEN (-100 4425);
DISPLAY INVISIBLE (-100 4425);
FORCEPROP 1 LAST HDL_TAP TRUE
J 2
(-425 4350);
DISPLAY 1.234043 (-425 4350);
PAINT GREEN (-425 4350);
DISPLAY INVISIBLE (-425 4350);
FORCEPROP 1 LAST PATH I133
J 2
(-98 4475);
DISPLAY 0.872340 (-98 4475);
PAINT GREEN (-98 4475);
DISPLAY INVISIBLE (-98 4475);
FORCEADD TAP..6
R 2
(-100 4425);
FORCEPROP 3 LASTPIN (-150 4425) SIG_NAME M_K_DQ<62>
J 0
(-140 4435);
DISPLAY 0.659574 (-140 4435);
PAINT MONO (-140 4435);
DISPLAY INVISIBLE (-140 4435);
FORCEPROP 1 LASTPIN (-150 4425) BN 62
J 2
(-100 4435);
DISPLAY 0.617021 (-100 4435);
PAINT PINK (-100 4435);
FORCEPROP 2 LAST CDS_LIB mstr_standard
J 2
(-100 4425);
DISPLAY 0.787234 (-100 4425);
PAINT MONO (-100 4425);
DISPLAY INVISIBLE (-100 4425);
FORCEPROP 1 LAST BODY_TYPE PLUMBING
J 2
(-100 4375);
DISPLAY 1.234043 (-100 4375);
PAINT GREEN (-100 4375);
DISPLAY INVISIBLE (-100 4375);
FORCEPROP 1 LAST HDL_TAP TRUE
J 2
(-425 4300);
DISPLAY 1.234043 (-425 4300);
PAINT GREEN (-425 4300);
DISPLAY INVISIBLE (-425 4300);
FORCEPROP 1 LAST PATH I134
J 2
(-98 4425);
DISPLAY 0.872340 (-98 4425);
PAINT GREEN (-98 4425);
DISPLAY INVISIBLE (-98 4425);
FORCEADD TAP..6
R 2
(-100 4375);
FORCEPROP 3 LASTPIN (-150 4375) SIG_NAME M_K_DQ<61>
J 0
(-140 4385);
DISPLAY 0.659574 (-140 4385);
PAINT MONO (-140 4385);
DISPLAY INVISIBLE (-140 4385);
FORCEPROP 1 LASTPIN (-150 4375) BN 61
J 2
(-100 4385);
DISPLAY 0.617021 (-100 4385);
PAINT PINK (-100 4385);
FORCEPROP 2 LAST CDS_LIB mstr_standard
J 2
(-100 4375);
DISPLAY 0.787234 (-100 4375);
PAINT MONO (-100 4375);
DISPLAY INVISIBLE (-100 4375);
FORCEPROP 1 LAST BODY_TYPE PLUMBING
J 2
(-100 4325);
DISPLAY 1.234043 (-100 4325);
PAINT GREEN (-100 4325);
DISPLAY INVISIBLE (-100 4325);
FORCEPROP 1 LAST HDL_TAP TRUE
J 2
(-425 4250);
DISPLAY 1.234043 (-425 4250);
PAINT GREEN (-425 4250);
DISPLAY INVISIBLE (-425 4250);
FORCEPROP 1 LAST PATH I135
J 2
(-98 4375);
DISPLAY 0.872340 (-98 4375);
PAINT GREEN (-98 4375);
DISPLAY INVISIBLE (-98 4375);
FORCEADD OFFPAGE..3
(500 4525);
FORCEPROP 2 LAST $XR0 60 
J 0
(714 4525);
DISPLAY 0.638298 (714 4525);
PAINT MONO (714 4525);
FORCEPROP 2 LAST $XR1 83 
J 0
(804 4525);
DISPLAY 0.638298 (804 4525);
PAINT MONO (804 4525);
FORCEPROP 2 LAST CDS_LIB mstr_standard
J 0
(500 4525);
DISPLAY 0.787234 (500 4525);
PAINT MONO (500 4525);
DISPLAY INVISIBLE (500 4525);
FORCEPROP 1 LAST OFFPAGE TRUE
J 0
(825 4400);
DISPLAY 0.936170 (825 4400);
PAINT GREEN (825 4400);
DISPLAY INVISIBLE (825 4400);
FORCEPROP 1 LAST COMMENT_BODY TRUE
J 0
(450 4425);
DISPLAY 0.936170 (450 4425);
PAINT GREEN (450 4425);
DISPLAY INVISIBLE (450 4425);
FORCEPROP 2 LAST PATH I136
J 0
(725 4575);
DISPLAY 1.021277 (725 4575);
PAINT ORANGE (725 4575);
DISPLAY INVISIBLE (725 4575);
FORCEADD GND..1
R 2
(2700 725);
FORCEPROP 3 LASTPIN (2700 775) SIG_NAME GND\g
J 0
(2710 785);
DISPLAY 0.659574 (2710 785);
PAINT MONO (2710 785);
DISPLAY INVISIBLE (2710 785);
FORCEPROP 1 LAST VOLTAGE 0
J 0
(2700 725);
PAINT SKYBLUE (2700 725);
DISPLAY INVISIBLE (2700 725);
FORCEPROP 2 LAST CDS_LIB mstr_symbols
J 0
(2700 725);
DISPLAY 0.787234 (2700 725);
PAINT MONO (2700 725);
DISPLAY INVISIBLE (2700 725);
FORCEPROP 1 LAST SIZE 1B
J 2
(2625 675);
DISPLAY 1.170213 (2625 675);
PAINT GREEN (2625 675);
DISPLAY INVISIBLE (2625 675);
FORCEPROP 2 LAST BOM_COST MEM
J 0
(2700 730);
PAINT ORANGE (2700 730);
DISPLAY INVISIBLE (2700 730);
FORCEPROP 1 LAST BODY_TYPE PLUMBING
J 2
(2745 682);
DISPLAY 0.340426 (2745 682);
PAINT GREEN (2745 682);
DISPLAY INVISIBLE (2745 682);
FORCEPROP 1 LAST PATH I137
J 2
(2625 725);
DISPLAY 0.872340 (2625 725);
PAINT AQUA (2625 725);
DISPLAY INVISIBLE (2625 725);
FORCEPROP 2 LAST ROOM DDR4_CH_C
J 0
(2700 730);
PAINT ORANGE (2700 730);
DISPLAY INVISIBLE (2700 730);
FORCEPROP 1 LAST HDL_POWER GND
J 2
(2700 875);
DISPLAY 0.553191 (2700 875);
PAINT GREEN (2700 875);
DISPLAY INVISIBLE (2700 875);
FORCEADD SCONN288_H44441003..3
(3400 2025);
FORCEPROP 1 LAST LOCATION J9M1
J 0
(2950 3425);
DISPLAY 0.617021 (2950 3425);
PAINT AQUA (2950 3425);
FORCEPROP 1 LAST PART_NUMBER H44441-003
J 0
(2950 675);
DISPLAY 0.617021 (2950 675);
PAINT BLUE (2950 675);
FORCEPROP 1 LAST MATERIAL SCONN
J 0
(2950 3375);
DISPLAY 0.617021 (2950 3375);
PAINT SKYBLUE (2950 3375);
FORCEPROP 2 LASTPIN (2900 3175) $PN 2
J 2
(2890 3185);
DISPLAY 0.617021 (2890 3185);
PAINT ORANGE (2890 3185);
FORCEPROP 2 LASTPIN (2900 3125) $PN 4
J 2
(2890 3135);
DISPLAY 0.617021 (2890 3135);
PAINT ORANGE (2890 3135);
FORCEPROP 2 LASTPIN (2900 3075) $PN 6
J 2
(2890 3085);
DISPLAY 0.617021 (2890 3085);
PAINT ORANGE (2890 3085);
FORCEPROP 2 LASTPIN (2900 3025) $PN 9
J 2
(2890 3035);
DISPLAY 0.617021 (2890 3035);
PAINT ORANGE (2890 3035);
FORCEPROP 2 LASTPIN (2900 2975) $PN 11
J 2
(2890 2985);
DISPLAY 0.617021 (2890 2985);
PAINT ORANGE (2890 2985);
FORCEPROP 2 LASTPIN (2900 2925) $PN 13
J 2
(2890 2935);
DISPLAY 0.617021 (2890 2935);
PAINT ORANGE (2890 2935);
FORCEPROP 2 LASTPIN (2900 2875) $PN 15
J 2
(2890 2885);
DISPLAY 0.617021 (2890 2885);
PAINT ORANGE (2890 2885);
FORCEPROP 2 LASTPIN (2900 2825) $PN 17
J 2
(2890 2835);
DISPLAY 0.617021 (2890 2835);
PAINT ORANGE (2890 2835);
FORCEPROP 2 LASTPIN (2900 2775) $PN 20
J 2
(2890 2785);
DISPLAY 0.617021 (2890 2785);
PAINT ORANGE (2890 2785);
FORCEPROP 2 LASTPIN (2900 2725) $PN 22
J 2
(2890 2735);
DISPLAY 0.617021 (2890 2735);
PAINT ORANGE (2890 2735);
FORCEPROP 2 LASTPIN (2900 2675) $PN 24
J 2
(2890 2685);
DISPLAY 0.617021 (2890 2685);
PAINT ORANGE (2890 2685);
FORCEPROP 2 LASTPIN (2900 2625) $PN 26
J 2
(2890 2635);
DISPLAY 0.617021 (2890 2635);
PAINT ORANGE (2890 2635);
FORCEPROP 2 LASTPIN (2900 2575) $PN 28
J 2
(2890 2585);
DISPLAY 0.617021 (2890 2585);
PAINT ORANGE (2890 2585);
FORCEPROP 2 LASTPIN (2900 2525) $PN 31
J 2
(2890 2535);
DISPLAY 0.617021 (2890 2535);
PAINT ORANGE (2890 2535);
FORCEPROP 2 LASTPIN (2900 2475) $PN 33
J 2
(2890 2485);
DISPLAY 0.617021 (2890 2485);
PAINT ORANGE (2890 2485);
FORCEPROP 2 LASTPIN (2900 2425) $PN 35
J 2
(2890 2435);
DISPLAY 0.617021 (2890 2435);
PAINT ORANGE (2890 2435);
FORCEPROP 2 LASTPIN (2900 2375) $PN 37
J 2
(2890 2385);
DISPLAY 0.617021 (2890 2385);
PAINT ORANGE (2890 2385);
FORCEPROP 2 LASTPIN (2900 2325) $PN 39
J 2
(2890 2335);
DISPLAY 0.617021 (2890 2335);
PAINT ORANGE (2890 2335);
FORCEPROP 2 LASTPIN (2900 2275) $PN 42
J 2
(2890 2285);
DISPLAY 0.617021 (2890 2285);
PAINT ORANGE (2890 2285);
FORCEPROP 2 LASTPIN (2900 2225) $PN 44
J 2
(2890 2235);
DISPLAY 0.617021 (2890 2235);
PAINT ORANGE (2890 2235);
FORCEPROP 2 LASTPIN (2900 2175) $PN 46
J 2
(2890 2185);
DISPLAY 0.617021 (2890 2185);
PAINT ORANGE (2890 2185);
FORCEPROP 2 LASTPIN (2900 2125) $PN 48
J 2
(2890 2135);
DISPLAY 0.617021 (2890 2135);
PAINT ORANGE (2890 2135);
FORCEPROP 2 LASTPIN (2900 2075) $PN 50
J 2
(2890 2085);
DISPLAY 0.617021 (2890 2085);
PAINT ORANGE (2890 2085);
FORCEPROP 2 LASTPIN (2900 2025) $PN 53
J 2
(2890 2035);
DISPLAY 0.617021 (2890 2035);
PAINT ORANGE (2890 2035);
FORCEPROP 2 LASTPIN (2900 1975) $PN 55
J 2
(2890 1985);
DISPLAY 0.617021 (2890 1985);
PAINT ORANGE (2890 1985);
FORCEPROP 2 LASTPIN (2900 1925) $PN 57
J 2
(2890 1935);
DISPLAY 0.617021 (2890 1935);
PAINT ORANGE (2890 1935);
FORCEPROP 2 LASTPIN (2900 1875) $PN 94
J 2
(2890 1885);
DISPLAY 0.617021 (2890 1885);
PAINT ORANGE (2890 1885);
FORCEPROP 2 LASTPIN (2900 1825) $PN 96
J 2
(2890 1835);
DISPLAY 0.617021 (2890 1835);
PAINT ORANGE (2890 1835);
FORCEPROP 2 LASTPIN (2900 1775) $PN 98
J 2
(2890 1785);
DISPLAY 0.617021 (2890 1785);
PAINT ORANGE (2890 1785);
FORCEPROP 2 LASTPIN (2900 1725) $PN 101
J 2
(2890 1735);
DISPLAY 0.617021 (2890 1735);
PAINT ORANGE (2890 1735);
FORCEPROP 2 LASTPIN (2900 1675) $PN 103
J 2
(2890 1685);
DISPLAY 0.617021 (2890 1685);
PAINT ORANGE (2890 1685);
FORCEPROP 2 LASTPIN (2900 1625) $PN 105
J 2
(2890 1635);
DISPLAY 0.617021 (2890 1635);
PAINT ORANGE (2890 1635);
FORCEPROP 2 LASTPIN (2900 1575) $PN 107
J 2
(2890 1585);
DISPLAY 0.617021 (2890 1585);
PAINT ORANGE (2890 1585);
FORCEPROP 2 LASTPIN (2900 1525) $PN 109
J 2
(2890 1535);
DISPLAY 0.617021 (2890 1535);
PAINT ORANGE (2890 1535);
FORCEPROP 2 LASTPIN (2900 1475) $PN 112
J 2
(2890 1485);
DISPLAY 0.617021 (2890 1485);
PAINT ORANGE (2890 1485);
FORCEPROP 2 LASTPIN (2900 1425) $PN 114
J 2
(2890 1435);
DISPLAY 0.617021 (2890 1435);
PAINT ORANGE (2890 1435);
FORCEPROP 2 LASTPIN (2900 1375) $PN 116
J 2
(2890 1385);
DISPLAY 0.617021 (2890 1385);
PAINT ORANGE (2890 1385);
FORCEPROP 2 LASTPIN (2900 1325) $PN 118
J 2
(2890 1335);
DISPLAY 0.617021 (2890 1335);
PAINT ORANGE (2890 1335);
FORCEPROP 2 LASTPIN (2900 1275) $PN 120
J 2
(2890 1285);
DISPLAY 0.617021 (2890 1285);
PAINT ORANGE (2890 1285);
FORCEPROP 2 LASTPIN (2900 1225) $PN 123
J 2
(2890 1235);
DISPLAY 0.617021 (2890 1235);
PAINT ORANGE (2890 1235);
FORCEPROP 2 LASTPIN (2900 1175) $PN 125
J 2
(2890 1185);
DISPLAY 0.617021 (2890 1185);
PAINT ORANGE (2890 1185);
FORCEPROP 2 LASTPIN (2900 1125) $PN 127
J 2
(2890 1135);
DISPLAY 0.617021 (2890 1135);
PAINT ORANGE (2890 1135);
FORCEPROP 2 LASTPIN (2900 1075) $PN 129
J 2
(2890 1085);
DISPLAY 0.617021 (2890 1085);
PAINT ORANGE (2890 1085);
FORCEPROP 2 LASTPIN (2900 1025) $PN 131
J 2
(2890 1035);
DISPLAY 0.617021 (2890 1035);
PAINT ORANGE (2890 1035);
FORCEPROP 2 LASTPIN (2900 975) $PN 134
J 2
(2890 985);
DISPLAY 0.617021 (2890 985);
PAINT ORANGE (2890 985);
FORCEPROP 2 LASTPIN (2900 925) $PN 136
J 2
(2890 935);
DISPLAY 0.617021 (2890 935);
PAINT ORANGE (2890 935);
FORCEPROP 2 LASTPIN (2900 875) $PN 138
J 2
(2890 885);
DISPLAY 0.617021 (2890 885);
PAINT ORANGE (2890 885);
FORCEPROP 2 LASTPIN (3900 3175) $PN 147
J 0
(3910 3185);
DISPLAY 0.617021 (3910 3185);
PAINT ORANGE (3910 3185);
FORCEPROP 2 LASTPIN (3900 3125) $PN 149
J 0
(3910 3135);
DISPLAY 0.617021 (3910 3135);
PAINT ORANGE (3910 3135);
FORCEPROP 2 LASTPIN (3900 3075) $PN 151
J 0
(3910 3085);
DISPLAY 0.617021 (3910 3085);
PAINT ORANGE (3910 3085);
FORCEPROP 2 LASTPIN (3900 3025) $PN 154
J 0
(3910 3035);
DISPLAY 0.617021 (3910 3035);
PAINT ORANGE (3910 3035);
FORCEPROP 2 LASTPIN (3900 2975) $PN 156
J 0
(3910 2985);
DISPLAY 0.617021 (3910 2985);
PAINT ORANGE (3910 2985);
FORCEPROP 2 LASTPIN (3900 2925) $PN 158
J 0
(3910 2935);
DISPLAY 0.617021 (3910 2935);
PAINT ORANGE (3910 2935);
FORCEPROP 2 LASTPIN (3900 2875) $PN 160
J 0
(3910 2885);
DISPLAY 0.617021 (3910 2885);
PAINT ORANGE (3910 2885);
FORCEPROP 2 LASTPIN (3900 2825) $PN 162
J 0
(3910 2835);
DISPLAY 0.617021 (3910 2835);
PAINT ORANGE (3910 2835);
FORCEPROP 2 LASTPIN (3900 2775) $PN 165
J 0
(3910 2785);
DISPLAY 0.617021 (3910 2785);
PAINT ORANGE (3910 2785);
FORCEPROP 2 LASTPIN (3900 2725) $PN 167
J 0
(3910 2735);
DISPLAY 0.617021 (3910 2735);
PAINT ORANGE (3910 2735);
FORCEPROP 2 LASTPIN (3900 2675) $PN 169
J 0
(3910 2685);
DISPLAY 0.617021 (3910 2685);
PAINT ORANGE (3910 2685);
FORCEPROP 2 LASTPIN (3900 2625) $PN 171
J 0
(3910 2635);
DISPLAY 0.617021 (3910 2635);
PAINT ORANGE (3910 2635);
FORCEPROP 2 LASTPIN (3900 2575) $PN 173
J 0
(3910 2585);
DISPLAY 0.617021 (3910 2585);
PAINT ORANGE (3910 2585);
FORCEPROP 2 LASTPIN (3900 2525) $PN 176
J 0
(3910 2535);
DISPLAY 0.617021 (3910 2535);
PAINT ORANGE (3910 2535);
FORCEPROP 2 LASTPIN (3900 2475) $PN 178
J 0
(3910 2485);
DISPLAY 0.617021 (3910 2485);
PAINT ORANGE (3910 2485);
FORCEPROP 2 LASTPIN (3900 2425) $PN 180
J 0
(3910 2435);
DISPLAY 0.617021 (3910 2435);
PAINT ORANGE (3910 2435);
FORCEPROP 2 LASTPIN (3900 2375) $PN 182
J 0
(3910 2385);
DISPLAY 0.617021 (3910 2385);
PAINT ORANGE (3910 2385);
FORCEPROP 2 LASTPIN (3900 2325) $PN 184
J 0
(3910 2335);
DISPLAY 0.617021 (3910 2335);
PAINT ORANGE (3910 2335);
FORCEPROP 2 LASTPIN (3900 2275) $PN 187
J 0
(3910 2285);
DISPLAY 0.617021 (3910 2285);
PAINT ORANGE (3910 2285);
FORCEPROP 2 LASTPIN (3900 2225) $PN 189
J 0
(3910 2235);
DISPLAY 0.617021 (3910 2235);
PAINT ORANGE (3910 2235);
FORCEPROP 2 LASTPIN (3900 2175) $PN 191
J 0
(3910 2185);
DISPLAY 0.617021 (3910 2185);
PAINT ORANGE (3910 2185);
FORCEPROP 2 LASTPIN (3900 2125) $PN 193
J 0
(3910 2135);
DISPLAY 0.617021 (3910 2135);
PAINT ORANGE (3910 2135);
FORCEPROP 2 LASTPIN (3900 2075) $PN 195
J 0
(3910 2085);
DISPLAY 0.617021 (3910 2085);
PAINT ORANGE (3910 2085);
FORCEPROP 2 LASTPIN (3900 2025) $PN 198
J 0
(3910 2035);
DISPLAY 0.617021 (3910 2035);
PAINT ORANGE (3910 2035);
FORCEPROP 2 LASTPIN (3900 1975) $PN 200
J 0
(3910 1985);
DISPLAY 0.617021 (3910 1985);
PAINT ORANGE (3910 1985);
FORCEPROP 2 LASTPIN (3900 1925) $PN 202
J 0
(3910 1935);
DISPLAY 0.617021 (3910 1935);
PAINT ORANGE (3910 1935);
FORCEPROP 2 LASTPIN (3900 1875) $PN 239
J 0
(3910 1885);
DISPLAY 0.617021 (3910 1885);
PAINT ORANGE (3910 1885);
FORCEPROP 2 LASTPIN (3900 1825) $PN 241
J 0
(3910 1835);
DISPLAY 0.617021 (3910 1835);
PAINT ORANGE (3910 1835);
FORCEPROP 2 LASTPIN (3900 1775) $PN 243
J 0
(3910 1785);
DISPLAY 0.617021 (3910 1785);
PAINT ORANGE (3910 1785);
FORCEPROP 2 LASTPIN (3900 1725) $PN 246
J 0
(3910 1735);
DISPLAY 0.617021 (3910 1735);
PAINT ORANGE (3910 1735);
FORCEPROP 2 LASTPIN (3900 1675) $PN 248
J 0
(3910 1685);
DISPLAY 0.617021 (3910 1685);
PAINT ORANGE (3910 1685);
FORCEPROP 2 LASTPIN (3900 1625) $PN 250
J 0
(3910 1635);
DISPLAY 0.617021 (3910 1635);
PAINT ORANGE (3910 1635);
FORCEPROP 2 LASTPIN (3900 1575) $PN 252
J 0
(3910 1585);
DISPLAY 0.617021 (3910 1585);
PAINT ORANGE (3910 1585);
FORCEPROP 2 LASTPIN (3900 1525) $PN 254
J 0
(3910 1535);
DISPLAY 0.617021 (3910 1535);
PAINT ORANGE (3910 1535);
FORCEPROP 2 LASTPIN (3900 1475) $PN 257
J 0
(3910 1485);
DISPLAY 0.617021 (3910 1485);
PAINT ORANGE (3910 1485);
FORCEPROP 2 LASTPIN (3900 1425) $PN 259
J 0
(3910 1435);
DISPLAY 0.617021 (3910 1435);
PAINT ORANGE (3910 1435);
FORCEPROP 2 LASTPIN (3900 1375) $PN 261
J 0
(3910 1385);
DISPLAY 0.617021 (3910 1385);
PAINT ORANGE (3910 1385);
FORCEPROP 2 LASTPIN (3900 1325) $PN 263
J 0
(3910 1335);
DISPLAY 0.617021 (3910 1335);
PAINT ORANGE (3910 1335);
FORCEPROP 2 LASTPIN (3900 1275) $PN 265
J 0
(3910 1285);
DISPLAY 0.617021 (3910 1285);
PAINT ORANGE (3910 1285);
FORCEPROP 2 LASTPIN (3900 1225) $PN 268
J 0
(3910 1235);
DISPLAY 0.617021 (3910 1235);
PAINT ORANGE (3910 1235);
FORCEPROP 2 LASTPIN (3900 1175) $PN 270
J 0
(3910 1185);
DISPLAY 0.617021 (3910 1185);
PAINT ORANGE (3910 1185);
FORCEPROP 2 LASTPIN (3900 1125) $PN 272
J 0
(3910 1135);
DISPLAY 0.617021 (3910 1135);
PAINT ORANGE (3910 1135);
FORCEPROP 2 LASTPIN (3900 1075) $PN 274
J 0
(3910 1085);
DISPLAY 0.617021 (3910 1085);
PAINT ORANGE (3910 1085);
FORCEPROP 2 LASTPIN (3900 1025) $PN 276
J 0
(3910 1035);
DISPLAY 0.617021 (3910 1035);
PAINT ORANGE (3910 1035);
FORCEPROP 2 LASTPIN (3900 975) $PN 279
J 0
(3910 985);
DISPLAY 0.617021 (3910 985);
PAINT ORANGE (3910 985);
FORCEPROP 2 LASTPIN (3900 925) $PN 281
J 0
(3910 935);
DISPLAY 0.617021 (3910 935);
PAINT ORANGE (3910 935);
FORCEPROP 2 LASTPIN (3900 875) $PN 283
J 0
(3910 885);
DISPLAY 0.617021 (3910 885);
PAINT ORANGE (3910 885);
FORCEPROP 1 LAST PACK_TYPE PIP
J 0
(2950 3475);
PAINT SKYBLUE (2950 3475);
DISPLAY INVISIBLE (2950 3475);
FORCEPROP 2 LAST BOM_COST MEM
J 0
(3400 2025);
PAINT ORANGE (3400 2025);
DISPLAY INVISIBLE (3400 2025);
FORCEPROP 2 LAST CDS_LIB mstr_sconn
J 0
(3400 2025);
PAINT ORANGE (3400 2025);
DISPLAY INVISIBLE (3400 2025);
FORCEPROP 2 LAST SEC_TYPE PIP
J 0
(2950 3475);
DISPLAY 1.021277 (2950 3475);
PAINT ORANGE (2950 3475);
DISPLAY INVISIBLE (2950 3475);
FORCEPROP 2 LAST SEC 3
J 0
(2950 3475);
DISPLAY 0.680851 (2950 3475);
PAINT MONO (2950 3475);
DISPLAY INVISIBLE (2950 3475);
FORCEPROP 2 LAST CDS_LOCATION J9M1
J 0
(2950 3425);
DISPLAY 0.617021 (2950 3425);
PAINT AQUA (2950 3425);
DISPLAY INVISIBLE (2950 3425);
FORCEPROP 1 LAST PATH I138
J 0
(3400 3375);
PAINT GREEN (3400 3375);
DISPLAY INVISIBLE (3400 3375);
FORCEPROP 2 LAST ROOM DDR4_CH_K
J 0
(3400 2025);
PAINT ORANGE (3400 2025);
DISPLAY INVISIBLE (3400 2025);
FORCEADD SCONN288_H44441003..1
(-850 2825);
FORCEPROP 1 LAST LOCATION J9M1
J 0
(-1300 4725);
DISPLAY 0.617021 (-1300 4725);
PAINT AQUA (-1300 4725);
FORCEPROP 1 LAST PART_NUMBER H44441-003
J 0
(-1300 825);
DISPLAY 0.617021 (-1300 825);
PAINT BLUE (-1300 825);
FORCEPROP 1 LAST MATERIAL SCONN
J 0
(-1300 4675);
DISPLAY 0.617021 (-1300 4675);
PAINT SKYBLUE (-1300 4675);
FORCEPROP 2 LASTPIN (-1350 1325) $PN 146
J 2
(-1360 1335);
DISPLAY 0.617021 (-1360 1335);
PAINT ORANGE (-1360 1335);
FORCEPROP 2 LASTPIN (-1350 1675) $PN 284
J 2
(-1360 1685);
DISPLAY 0.617021 (-1360 1685);
PAINT ORANGE (-1360 1685);
FORCEPROP 2 LASTPIN (-1350 1475) $PN 285
J 2
(-1360 1485);
DISPLAY 0.617021 (-1360 1485);
PAINT ORANGE (-1360 1485);
FORCEPROP 2 LASTPIN (-1350 1425) $PN 141
J 2
(-1360 1435);
DISPLAY 0.617021 (-1360 1435);
PAINT ORANGE (-1360 1435);
FORCEPROP 2 LASTPIN (-1350 1025) $PN 230
J 2
(-1360 1035);
DISPLAY 0.617021 (-1360 1035);
PAINT ORANGE (-1360 1035);
FORCEPROP 2 LASTPIN (-1350 1625) $PN 238
J 2
(-1360 1635);
DISPLAY 0.617021 (-1360 1635);
PAINT ORANGE (-1360 1635);
FORCEPROP 2 LASTPIN (-1350 1575) $PN 140
J 2
(-1360 1585);
DISPLAY 0.617021 (-1360 1585);
PAINT ORANGE (-1360 1585);
FORCEPROP 2 LASTPIN (-1350 1525) $PN 139
J 2
(-1360 1535);
DISPLAY 0.617021 (-1360 1535);
PAINT ORANGE (-1360 1535);
FORCEPROP 2 LASTPIN (-1350 2975) $PN 237
J 2
(-1360 2985);
DISPLAY 0.617021 (-1360 2985);
PAINT ORANGE (-1360 2985);
FORCEPROP 2 LASTPIN (-1350 2925) $PN 93
J 2
(-1360 2935);
DISPLAY 0.617021 (-1360 2935);
PAINT ORANGE (-1360 2935);
FORCEPROP 2 LASTPIN (-1350 2875) $PN 89
J 2
(-1360 2885);
DISPLAY 0.617021 (-1360 2885);
PAINT ORANGE (-1360 2885);
FORCEPROP 2 LASTPIN (-1350 2825) $PN 84
J 2
(-1360 2835);
DISPLAY 0.617021 (-1360 2835);
PAINT ORANGE (-1360 2835);
FORCEPROP 2 LASTPIN (-1350 1225) $PN 144
J 2
(-1360 1235);
DISPLAY 0.617021 (-1360 1235);
PAINT ORANGE (-1360 1235);
FORCEPROP 2 LASTPIN (-1350 1175) $PN 227
J 2
(-1360 1185);
DISPLAY 0.617021 (-1360 1185);
PAINT ORANGE (-1360 1185);
FORCEPROP 2 LASTPIN (-1350 1125) $PN 205
J 2
(-1360 1135);
DISPLAY 0.617021 (-1360 1135);
PAINT ORANGE (-1360 1135);
FORCEPROP 2 LASTPIN (-1350 1925) $PN 58
J 2
(-1360 1935);
DISPLAY 0.617021 (-1360 1935);
PAINT ORANGE (-1360 1935);
FORCEPROP 2 LASTPIN (-1350 1975) $PN 222
J 2
(-1360 1985);
DISPLAY 0.617021 (-1360 1985);
PAINT ORANGE (-1360 1985);
FORCEPROP 2 LASTPIN (-1350 2575) $PN 91
J 2
(-1360 2585);
DISPLAY 0.617021 (-1360 2585);
PAINT ORANGE (-1360 2585);
FORCEPROP 2 LASTPIN (-1350 2525) $PN 87
J 2
(-1360 2535);
DISPLAY 0.617021 (-1360 2535);
PAINT ORANGE (-1360 2535);
FORCEPROP 2 LASTPIN (-1350 1875) $PN 78
J 2
(-1360 1885);
DISPLAY 0.617021 (-1360 1885);
PAINT ORANGE (-1360 1885);
FORCEPROP 2 LASTPIN (-350 4475) $PN 280
J 0
(-340 4485);
DISPLAY 0.617021 (-340 4485);
PAINT ORANGE (-340 4485);
FORCEPROP 2 LASTPIN (-350 4425) $PN 135
J 0
(-340 4435);
DISPLAY 0.617021 (-340 4435);
PAINT ORANGE (-340 4435);
FORCEPROP 2 LASTPIN (-350 4375) $PN 273
J 0
(-340 4385);
DISPLAY 0.617021 (-340 4385);
PAINT ORANGE (-340 4385);
FORCEPROP 2 LASTPIN (-350 4325) $PN 128
J 0
(-340 4335);
DISPLAY 0.617021 (-340 4335);
PAINT ORANGE (-340 4335);
FORCEPROP 2 LASTPIN (-350 4275) $PN 282
J 0
(-340 4285);
DISPLAY 0.617021 (-340 4285);
PAINT ORANGE (-340 4285);
FORCEPROP 2 LASTPIN (-350 4225) $PN 137
J 0
(-340 4235);
DISPLAY 0.617021 (-340 4235);
PAINT ORANGE (-340 4235);
FORCEPROP 2 LASTPIN (-350 4175) $PN 275
J 0
(-340 4185);
DISPLAY 0.617021 (-340 4185);
PAINT ORANGE (-340 4185);
FORCEPROP 2 LASTPIN (-350 4125) $PN 130
J 0
(-340 4135);
DISPLAY 0.617021 (-340 4135);
PAINT ORANGE (-340 4135);
FORCEPROP 2 LASTPIN (-350 4075) $PN 269
J 0
(-340 4085);
DISPLAY 0.617021 (-340 4085);
PAINT ORANGE (-340 4085);
FORCEPROP 2 LASTPIN (-350 4025) $PN 124
J 0
(-340 4035);
DISPLAY 0.617021 (-340 4035);
PAINT ORANGE (-340 4035);
FORCEPROP 2 LASTPIN (-350 3975) $PN 262
J 0
(-340 3985);
DISPLAY 0.617021 (-340 3985);
PAINT ORANGE (-340 3985);
FORCEPROP 2 LASTPIN (-350 3925) $PN 117
J 0
(-340 3935);
DISPLAY 0.617021 (-340 3935);
PAINT ORANGE (-340 3935);
FORCEPROP 2 LASTPIN (-350 3875) $PN 271
J 0
(-340 3885);
DISPLAY 0.617021 (-340 3885);
PAINT ORANGE (-340 3885);
FORCEPROP 2 LASTPIN (-350 3825) $PN 126
J 0
(-340 3835);
DISPLAY 0.617021 (-340 3835);
PAINT ORANGE (-340 3835);
FORCEPROP 2 LASTPIN (-350 3775) $PN 264
J 0
(-340 3785);
DISPLAY 0.617021 (-340 3785);
PAINT ORANGE (-340 3785);
FORCEPROP 2 LASTPIN (-350 3725) $PN 119
J 0
(-340 3735);
DISPLAY 0.617021 (-340 3735);
PAINT ORANGE (-340 3735);
FORCEPROP 2 LASTPIN (-350 3675) $PN 258
J 0
(-340 3685);
DISPLAY 0.617021 (-340 3685);
PAINT ORANGE (-340 3685);
FORCEPROP 2 LASTPIN (-350 3625) $PN 113
J 0
(-340 3635);
DISPLAY 0.617021 (-340 3635);
PAINT ORANGE (-340 3635);
FORCEPROP 2 LASTPIN (-350 3575) $PN 251
J 0
(-340 3585);
DISPLAY 0.617021 (-340 3585);
PAINT ORANGE (-340 3585);
FORCEPROP 2 LASTPIN (-350 3525) $PN 106
J 0
(-340 3535);
DISPLAY 0.617021 (-340 3535);
PAINT ORANGE (-340 3535);
FORCEPROP 2 LASTPIN (-350 3475) $PN 260
J 0
(-340 3485);
DISPLAY 0.617021 (-340 3485);
PAINT ORANGE (-340 3485);
FORCEPROP 2 LASTPIN (-350 3425) $PN 115
J 0
(-340 3435);
DISPLAY 0.617021 (-340 3435);
PAINT ORANGE (-340 3435);
FORCEPROP 2 LASTPIN (-350 3375) $PN 253
J 0
(-340 3385);
DISPLAY 0.617021 (-340 3385);
PAINT ORANGE (-340 3385);
FORCEPROP 2 LASTPIN (-350 3325) $PN 108
J 0
(-340 3335);
DISPLAY 0.617021 (-340 3335);
PAINT ORANGE (-340 3335);
FORCEPROP 2 LASTPIN (-350 3275) $PN 247
J 0
(-340 3285);
DISPLAY 0.617021 (-340 3285);
PAINT ORANGE (-340 3285);
FORCEPROP 2 LASTPIN (-350 3225) $PN 102
J 0
(-340 3235);
DISPLAY 0.617021 (-340 3235);
PAINT ORANGE (-340 3235);
FORCEPROP 2 LASTPIN (-350 3175) $PN 240
J 0
(-340 3185);
DISPLAY 0.617021 (-340 3185);
PAINT ORANGE (-340 3185);
FORCEPROP 2 LASTPIN (-350 3125) $PN 95
J 0
(-340 3135);
DISPLAY 0.617021 (-340 3135);
PAINT ORANGE (-340 3135);
FORCEPROP 2 LASTPIN (-350 3075) $PN 249
J 0
(-340 3085);
DISPLAY 0.617021 (-340 3085);
PAINT ORANGE (-340 3085);
FORCEPROP 2 LASTPIN (-350 3025) $PN 104
J 0
(-340 3035);
DISPLAY 0.617021 (-340 3035);
PAINT ORANGE (-340 3035);
FORCEPROP 2 LASTPIN (-350 2975) $PN 242
J 0
(-340 2985);
DISPLAY 0.617021 (-340 2985);
PAINT ORANGE (-340 2985);
FORCEPROP 2 LASTPIN (-350 2925) $PN 97
J 0
(-340 2935);
DISPLAY 0.617021 (-340 2935);
PAINT ORANGE (-340 2935);
FORCEPROP 2 LASTPIN (-350 2875) $PN 188
J 0
(-340 2885);
DISPLAY 0.617021 (-340 2885);
PAINT ORANGE (-340 2885);
FORCEPROP 2 LASTPIN (-350 2825) $PN 43
J 0
(-340 2835);
DISPLAY 0.617021 (-340 2835);
PAINT ORANGE (-340 2835);
FORCEPROP 2 LASTPIN (-350 2775) $PN 181
J 0
(-340 2785);
DISPLAY 0.617021 (-340 2785);
PAINT ORANGE (-340 2785);
FORCEPROP 2 LASTPIN (-350 2725) $PN 36
J 0
(-340 2735);
DISPLAY 0.617021 (-340 2735);
PAINT ORANGE (-340 2735);
FORCEPROP 2 LASTPIN (-350 2675) $PN 190
J 0
(-340 2685);
DISPLAY 0.617021 (-340 2685);
PAINT ORANGE (-340 2685);
FORCEPROP 2 LASTPIN (-350 2625) $PN 45
J 0
(-340 2635);
DISPLAY 0.617021 (-340 2635);
PAINT ORANGE (-340 2635);
FORCEPROP 2 LASTPIN (-350 2575) $PN 183
J 0
(-340 2585);
DISPLAY 0.617021 (-340 2585);
PAINT ORANGE (-340 2585);
FORCEPROP 2 LASTPIN (-350 2525) $PN 38
J 0
(-340 2535);
DISPLAY 0.617021 (-340 2535);
PAINT ORANGE (-340 2535);
FORCEPROP 2 LASTPIN (-350 2475) $PN 177
J 0
(-340 2485);
DISPLAY 0.617021 (-340 2485);
PAINT ORANGE (-340 2485);
FORCEPROP 2 LASTPIN (-350 2425) $PN 32
J 0
(-340 2435);
DISPLAY 0.617021 (-340 2435);
PAINT ORANGE (-340 2435);
FORCEPROP 2 LASTPIN (-350 2375) $PN 170
J 0
(-340 2385);
DISPLAY 0.617021 (-340 2385);
PAINT ORANGE (-340 2385);
FORCEPROP 2 LASTPIN (-350 2325) $PN 25
J 0
(-340 2335);
DISPLAY 0.617021 (-340 2335);
PAINT ORANGE (-340 2335);
FORCEPROP 2 LASTPIN (-350 2275) $PN 179
J 0
(-340 2285);
DISPLAY 0.617021 (-340 2285);
PAINT ORANGE (-340 2285);
FORCEPROP 2 LASTPIN (-350 2225) $PN 34
J 0
(-340 2235);
DISPLAY 0.617021 (-340 2235);
PAINT ORANGE (-340 2235);
FORCEPROP 2 LASTPIN (-350 2175) $PN 172
J 0
(-340 2185);
DISPLAY 0.617021 (-340 2185);
PAINT ORANGE (-340 2185);
FORCEPROP 2 LASTPIN (-350 2125) $PN 27
J 0
(-340 2135);
DISPLAY 0.617021 (-340 2135);
PAINT ORANGE (-340 2135);
FORCEPROP 2 LASTPIN (-350 2075) $PN 166
J 0
(-340 2085);
DISPLAY 0.617021 (-340 2085);
PAINT ORANGE (-340 2085);
FORCEPROP 2 LASTPIN (-350 2025) $PN 21
J 0
(-340 2035);
DISPLAY 0.617021 (-340 2035);
PAINT ORANGE (-340 2035);
FORCEPROP 2 LASTPIN (-350 1975) $PN 159
J 0
(-340 1985);
DISPLAY 0.617021 (-340 1985);
PAINT ORANGE (-340 1985);
FORCEPROP 2 LASTPIN (-350 1925) $PN 14
J 0
(-340 1935);
DISPLAY 0.617021 (-340 1935);
PAINT ORANGE (-340 1935);
FORCEPROP 2 LASTPIN (-350 1875) $PN 168
J 0
(-340 1885);
DISPLAY 0.617021 (-340 1885);
PAINT ORANGE (-340 1885);
FORCEPROP 2 LASTPIN (-350 1825) $PN 23
J 0
(-340 1835);
DISPLAY 0.617021 (-340 1835);
PAINT ORANGE (-340 1835);
FORCEPROP 2 LASTPIN (-350 1775) $PN 161
J 0
(-340 1785);
DISPLAY 0.617021 (-340 1785);
PAINT ORANGE (-340 1785);
FORCEPROP 2 LASTPIN (-350 1725) $PN 16
J 0
(-340 1735);
DISPLAY 0.617021 (-340 1735);
PAINT ORANGE (-340 1735);
FORCEPROP 2 LASTPIN (-350 1675) $PN 155
J 0
(-340 1685);
DISPLAY 0.617021 (-340 1685);
PAINT ORANGE (-340 1685);
FORCEPROP 2 LASTPIN (-350 1625) $PN 10
J 0
(-340 1635);
DISPLAY 0.617021 (-340 1635);
PAINT ORANGE (-340 1635);
FORCEPROP 2 LASTPIN (-350 1575) $PN 148
J 0
(-340 1585);
DISPLAY 0.617021 (-340 1585);
PAINT ORANGE (-340 1585);
FORCEPROP 2 LASTPIN (-350 1525) $PN 3
J 0
(-340 1535);
DISPLAY 0.617021 (-340 1535);
PAINT ORANGE (-340 1535);
FORCEPROP 2 LASTPIN (-350 1475) $PN 157
J 0
(-340 1485);
DISPLAY 0.617021 (-340 1485);
PAINT ORANGE (-340 1485);
FORCEPROP 2 LASTPIN (-350 1425) $PN 12
J 0
(-340 1435);
DISPLAY 0.617021 (-340 1435);
PAINT ORANGE (-340 1435);
FORCEPROP 2 LASTPIN (-350 1375) $PN 150
J 0
(-340 1385);
DISPLAY 0.617021 (-340 1385);
PAINT ORANGE (-340 1385);
FORCEPROP 2 LASTPIN (-350 1325) $PN 5
J 0
(-340 1335);
DISPLAY 0.617021 (-340 1335);
PAINT ORANGE (-340 1335);
FORCEPROP 2 LASTPIN (-1350 2725) $PN 203
J 2
(-1360 2735);
DISPLAY 0.617021 (-1360 2735);
PAINT ORANGE (-1360 2735);
FORCEPROP 2 LASTPIN (-1350 2675) $PN 60
J 2
(-1360 2685);
DISPLAY 0.617021 (-1360 2685);
PAINT ORANGE (-1360 2685);
FORCEPROP 2 LASTPIN (-1350 3275) $PN 218
J 2
(-1360 3285);
DISPLAY 0.617021 (-1360 3285);
PAINT ORANGE (-1360 3285);
FORCEPROP 2 LASTPIN (-1350 3225) $PN 219
J 2
(-1360 3235);
DISPLAY 0.617021 (-1360 3235);
PAINT ORANGE (-1360 3235);
FORCEPROP 2 LASTPIN (-1350 3175) $PN 74
J 2
(-1360 3185);
DISPLAY 0.617021 (-1360 3185);
PAINT ORANGE (-1360 3185);
FORCEPROP 2 LASTPIN (-1350 3125) $PN 75
J 2
(-1360 3135);
DISPLAY 0.617021 (-1360 3135);
PAINT ORANGE (-1360 3135);
FORCEPROP 2 LASTPIN (-1350 2425) $PN 199
J 2
(-1360 2435);
DISPLAY 0.617021 (-1360 2435);
PAINT ORANGE (-1360 2435);
FORCEPROP 2 LASTPIN (-1350 2375) $PN 54
J 2
(-1360 2385);
DISPLAY 0.617021 (-1360 2385);
PAINT ORANGE (-1360 2385);
FORCEPROP 2 LASTPIN (-1350 2325) $PN 192
J 2
(-1360 2335);
DISPLAY 0.617021 (-1360 2335);
PAINT ORANGE (-1360 2335);
FORCEPROP 2 LASTPIN (-1350 2275) $PN 47
J 2
(-1360 2285);
DISPLAY 0.617021 (-1360 2285);
PAINT ORANGE (-1360 2285);
FORCEPROP 2 LASTPIN (-1350 2225) $PN 201
J 2
(-1360 2235);
DISPLAY 0.617021 (-1360 2235);
PAINT ORANGE (-1360 2235);
FORCEPROP 2 LASTPIN (-1350 2175) $PN 56
J 2
(-1360 2185);
DISPLAY 0.617021 (-1360 2185);
PAINT ORANGE (-1360 2185);
FORCEPROP 2 LASTPIN (-1350 2125) $PN 194
J 2
(-1360 2135);
DISPLAY 0.617021 (-1360 2135);
PAINT ORANGE (-1360 2135);
FORCEPROP 2 LASTPIN (-1350 2075) $PN 49
J 2
(-1360 2085);
DISPLAY 0.617021 (-1360 2085);
PAINT ORANGE (-1360 2085);
FORCEPROP 2 LASTPIN (-1350 3025) $PN 235
J 2
(-1360 3035);
DISPLAY 0.617021 (-1360 3035);
PAINT ORANGE (-1360 3035);
FORCEPROP 2 LASTPIN (-1350 3425) $PN 207
J 2
(-1360 3435);
DISPLAY 0.617021 (-1360 3435);
PAINT ORANGE (-1360 3435);
FORCEPROP 2 LASTPIN (-1350 3375) $PN 63
J 2
(-1360 3385);
DISPLAY 0.617021 (-1360 3385);
PAINT ORANGE (-1360 3385);
FORCEPROP 2 LASTPIN (-1350 3525) $PN 224
J 2
(-1360 3535);
DISPLAY 0.617021 (-1360 3535);
PAINT ORANGE (-1360 3535);
FORCEPROP 2 LASTPIN (-1350 3475) $PN 81
J 2
(-1360 3485);
DISPLAY 0.617021 (-1360 3485);
PAINT ORANGE (-1360 3485);
FORCEPROP 2 LASTPIN (-1350 1825) $PN 208
J 2
(-1360 1835);
DISPLAY 0.617021 (-1360 1835);
PAINT ORANGE (-1360 1835);
FORCEPROP 2 LASTPIN (-1350 1775) $PN 62
J 2
(-1360 1785);
DISPLAY 0.617021 (-1360 1785);
PAINT ORANGE (-1360 1785);
FORCEPROP 2 LASTPIN (-1350 4475) $PN 234
J 2
(-1360 4485);
DISPLAY 0.617021 (-1360 4485);
PAINT ORANGE (-1360 4485);
FORCEPROP 2 LASTPIN (-1350 4425) $PN 82
J 2
(-1360 4435);
DISPLAY 0.617021 (-1360 4435);
PAINT ORANGE (-1360 4435);
FORCEPROP 2 LASTPIN (-1350 4375) $PN 86
J 2
(-1360 4385);
DISPLAY 0.617021 (-1360 4385);
PAINT ORANGE (-1360 4385);
FORCEPROP 2 LASTPIN (-1350 4325) $PN 228
J 2
(-1360 4335);
DISPLAY 0.617021 (-1360 4335);
PAINT ORANGE (-1360 4335);
FORCEPROP 2 LASTPIN (-1350 4275) $PN 232
J 2
(-1360 4285);
DISPLAY 0.617021 (-1360 4285);
PAINT ORANGE (-1360 4285);
FORCEPROP 2 LASTPIN (-1350 4225) $PN 65
J 2
(-1360 4235);
DISPLAY 0.617021 (-1360 4235);
PAINT ORANGE (-1360 4235);
FORCEPROP 2 LASTPIN (-1350 4175) $PN 210
J 2
(-1360 4185);
DISPLAY 0.617021 (-1360 4185);
PAINT ORANGE (-1360 4185);
FORCEPROP 2 LASTPIN (-1350 4125) $PN 225
J 2
(-1360 4135);
DISPLAY 0.617021 (-1360 4135);
PAINT ORANGE (-1360 4135);
FORCEPROP 2 LASTPIN (-1350 4075) $PN 66
J 2
(-1360 4085);
DISPLAY 0.617021 (-1360 4085);
PAINT ORANGE (-1360 4085);
FORCEPROP 2 LASTPIN (-1350 4025) $PN 68
J 2
(-1360 4035);
DISPLAY 0.617021 (-1360 4035);
PAINT ORANGE (-1360 4035);
FORCEPROP 2 LASTPIN (-1350 3975) $PN 211
J 2
(-1360 3985);
DISPLAY 0.617021 (-1360 3985);
PAINT ORANGE (-1360 3985);
FORCEPROP 2 LASTPIN (-1350 3925) $PN 69
J 2
(-1360 3935);
DISPLAY 0.617021 (-1360 3935);
PAINT ORANGE (-1360 3935);
FORCEPROP 2 LASTPIN (-1350 3875) $PN 213
J 2
(-1360 3885);
DISPLAY 0.617021 (-1360 3885);
PAINT ORANGE (-1360 3885);
FORCEPROP 2 LASTPIN (-1350 3825) $PN 214
J 2
(-1360 3835);
DISPLAY 0.617021 (-1360 3835);
PAINT ORANGE (-1360 3835);
FORCEPROP 2 LASTPIN (-1350 3775) $PN 71
J 2
(-1360 3785);
DISPLAY 0.617021 (-1360 3785);
PAINT ORANGE (-1360 3785);
FORCEPROP 2 LASTPIN (-1350 3725) $PN 216
J 2
(-1360 3735);
DISPLAY 0.617021 (-1360 3735);
PAINT ORANGE (-1360 3735);
FORCEPROP 2 LASTPIN (-1350 3675) $PN 72
J 2
(-1360 3685);
DISPLAY 0.617021 (-1360 3685);
PAINT ORANGE (-1360 3685);
FORCEPROP 2 LASTPIN (-1350 3625) $PN 79
J 2
(-1360 3635);
DISPLAY 0.617021 (-1360 3635);
PAINT ORANGE (-1360 3635);
FORCEPROP 1 LAST PACK_TYPE PIP
J 0
(-1300 4775);
PAINT SKYBLUE (-1300 4775);
DISPLAY INVISIBLE (-1300 4775);
FORCEPROP 2 LAST BOM_COST MEM
J 0
(-850 2825);
PAINT ORANGE (-850 2825);
DISPLAY INVISIBLE (-850 2825);
FORCEPROP 2 LAST CDS_LIB mstr_sconn
J 0
(-850 2825);
PAINT ORANGE (-850 2825);
DISPLAY INVISIBLE (-850 2825);
FORCEPROP 2 LAST SEC_TYPE PIP
J 0
(-1300 4775);
DISPLAY 1.021277 (-1300 4775);
PAINT ORANGE (-1300 4775);
DISPLAY INVISIBLE (-1300 4775);
FORCEPROP 2 LAST SEC 1
J 0
(-1300 4775);
DISPLAY 0.680851 (-1300 4775);
PAINT MONO (-1300 4775);
DISPLAY INVISIBLE (-1300 4775);
FORCEPROP 2 LAST CDS_LOCATION J9M1
J 0
(-1300 4725);
DISPLAY 0.617021 (-1300 4725);
PAINT AQUA (-1300 4725);
DISPLAY INVISIBLE (-1300 4725);
FORCEPROP 1 LAST PATH I14
J 0
(-850 4675);
PAINT GREEN (-850 4675);
DISPLAY INVISIBLE (-850 4675);
FORCEPROP 2 LAST ROOM DDR4_CH_K
J 0
(-850 2825);
PAINT ORANGE (-850 2825);
DISPLAY INVISIBLE (-850 2825);
FORCEADD TAP..6
R 2
(2300 3125);
FORCEPROP 3 LASTPIN (2250 3125) SIG_NAME M_K_DQS_DP<0>
J 0
(2260 3135);
DISPLAY 0.659574 (2260 3135);
PAINT MONO (2260 3135);
DISPLAY INVISIBLE (2260 3135);
FORCEPROP 1 LASTPIN (2250 3125) BN 0
J 2
(2300 3135);
DISPLAY 0.617021 (2300 3135);
PAINT PINK (2300 3135);
FORCEPROP 2 LAST CDS_LIB mstr_standard
J 0
(2300 3125);
DISPLAY 0.787234 (2300 3125);
PAINT MONO (2300 3125);
DISPLAY INVISIBLE (2300 3125);
FORCEPROP 1 LAST BODY_TYPE PLUMBING
J 2
(2300 3075);
DISPLAY 1.234043 (2300 3075);
PAINT GREEN (2300 3075);
DISPLAY INVISIBLE (2300 3075);
FORCEPROP 1 LAST HDL_TAP TRUE
J 2
(1975 3000);
DISPLAY 1.234043 (1975 3000);
PAINT GREEN (1975 3000);
DISPLAY INVISIBLE (1975 3000);
FORCEPROP 1 LAST PATH I142
J 2
(2302 3125);
DISPLAY 0.872340 (2302 3125);
PAINT GREEN (2302 3125);
DISPLAY INVISIBLE (2302 3125);
FORCEADD TAP..6
R 2
(2500 3075);
FORCEPROP 3 LASTPIN (2450 3075) SIG_NAME M_K_DQS_DN<0>
J 0
(2460 3085);
DISPLAY 0.659574 (2460 3085);
PAINT MONO (2460 3085);
DISPLAY INVISIBLE (2460 3085);
FORCEPROP 1 LASTPIN (2450 3075) BN 0
J 2
(2500 3085);
DISPLAY 0.617021 (2500 3085);
PAINT PINK (2500 3085);
FORCEPROP 2 LAST CDS_LIB mstr_standard
J 0
(2500 3075);
DISPLAY 0.787234 (2500 3075);
PAINT MONO (2500 3075);
DISPLAY INVISIBLE (2500 3075);
FORCEPROP 1 LAST BODY_TYPE PLUMBING
J 2
(2500 3025);
DISPLAY 1.234043 (2500 3025);
PAINT GREEN (2500 3025);
DISPLAY INVISIBLE (2500 3025);
FORCEPROP 1 LAST HDL_TAP TRUE
J 2
(2175 2950);
DISPLAY 1.234043 (2175 2950);
PAINT GREEN (2175 2950);
DISPLAY INVISIBLE (2175 2950);
FORCEPROP 1 LAST PATH I143
J 2
(2502 3075);
DISPLAY 0.872340 (2502 3075);
PAINT GREEN (2502 3075);
DISPLAY INVISIBLE (2502 3075);
FORCEADD TAP..6
R 2
(2500 3175);
FORCEPROP 3 LASTPIN (2450 3175) SIG_NAME M_K_DQS_DN<1>
J 0
(2460 3185);
DISPLAY 0.659574 (2460 3185);
PAINT MONO (2460 3185);
DISPLAY INVISIBLE (2460 3185);
FORCEPROP 1 LASTPIN (2450 3175) BN 1
J 2
(2500 3185);
DISPLAY 0.617021 (2500 3185);
PAINT PINK (2500 3185);
FORCEPROP 2 LAST CDS_LIB mstr_standard
J 0
(2500 3175);
DISPLAY 0.787234 (2500 3175);
PAINT MONO (2500 3175);
DISPLAY INVISIBLE (2500 3175);
FORCEPROP 1 LAST BODY_TYPE PLUMBING
J 2
(2500 3125);
DISPLAY 1.234043 (2500 3125);
PAINT GREEN (2500 3125);
DISPLAY INVISIBLE (2500 3125);
FORCEPROP 1 LAST HDL_TAP TRUE
J 2
(2175 3050);
DISPLAY 1.234043 (2175 3050);
PAINT GREEN (2175 3050);
DISPLAY INVISIBLE (2175 3050);
FORCEPROP 1 LAST PATH I144
J 2
(2502 3175);
DISPLAY 0.872340 (2502 3175);
PAINT GREEN (2502 3175);
DISPLAY INVISIBLE (2502 3175);
FORCEADD TAP..6
R 2
(2300 3325);
FORCEPROP 3 LASTPIN (2250 3325) SIG_NAME M_K_DQS_DP<2>
J 0
(2260 3335);
DISPLAY 0.659574 (2260 3335);
PAINT MONO (2260 3335);
DISPLAY INVISIBLE (2260 3335);
FORCEPROP 1 LASTPIN (2250 3325) BN 2
J 2
(2300 3335);
DISPLAY 0.617021 (2300 3335);
PAINT PINK (2300 3335);
FORCEPROP 2 LAST CDS_LIB mstr_standard
J 0
(2300 3325);
DISPLAY 0.787234 (2300 3325);
PAINT MONO (2300 3325);
DISPLAY INVISIBLE (2300 3325);
FORCEPROP 1 LAST BODY_TYPE PLUMBING
J 2
(2300 3275);
DISPLAY 1.234043 (2300 3275);
PAINT GREEN (2300 3275);
DISPLAY INVISIBLE (2300 3275);
FORCEPROP 1 LAST HDL_TAP TRUE
J 2
(1975 3200);
DISPLAY 1.234043 (1975 3200);
PAINT GREEN (1975 3200);
DISPLAY INVISIBLE (1975 3200);
FORCEPROP 1 LAST PATH I145
J 2
(2302 3325);
DISPLAY 0.872340 (2302 3325);
PAINT GREEN (2302 3325);
DISPLAY INVISIBLE (2302 3325);
FORCEADD TAP..6
R 2
(2300 3225);
FORCEPROP 3 LASTPIN (2250 3225) SIG_NAME M_K_DQS_DP<1>
J 0
(2260 3235);
DISPLAY 0.659574 (2260 3235);
PAINT MONO (2260 3235);
DISPLAY INVISIBLE (2260 3235);
FORCEPROP 1 LASTPIN (2250 3225) BN 1
J 2
(2300 3235);
DISPLAY 0.617021 (2300 3235);
PAINT PINK (2300 3235);
FORCEPROP 2 LAST CDS_LIB mstr_standard
J 0
(2300 3225);
DISPLAY 0.787234 (2300 3225);
PAINT MONO (2300 3225);
DISPLAY INVISIBLE (2300 3225);
FORCEPROP 1 LAST BODY_TYPE PLUMBING
J 2
(2300 3175);
DISPLAY 1.234043 (2300 3175);
PAINT GREEN (2300 3175);
DISPLAY INVISIBLE (2300 3175);
FORCEPROP 1 LAST HDL_TAP TRUE
J 2
(1975 3100);
DISPLAY 1.234043 (1975 3100);
PAINT GREEN (1975 3100);
DISPLAY INVISIBLE (1975 3100);
FORCEPROP 1 LAST PATH I146
J 2
(2302 3225);
DISPLAY 0.872340 (2302 3225);
PAINT GREEN (2302 3225);
DISPLAY INVISIBLE (2302 3225);
FORCEADD TAP..6
R 2
(2300 3425);
FORCEPROP 3 LASTPIN (2250 3425) SIG_NAME M_K_DQS_DP<3>
J 0
(2260 3435);
DISPLAY 0.659574 (2260 3435);
PAINT MONO (2260 3435);
DISPLAY INVISIBLE (2260 3435);
FORCEPROP 1 LASTPIN (2250 3425) BN 3
J 2
(2300 3435);
DISPLAY 0.617021 (2300 3435);
PAINT PINK (2300 3435);
FORCEPROP 2 LAST CDS_LIB mstr_standard
J 0
(2300 3425);
DISPLAY 0.787234 (2300 3425);
PAINT MONO (2300 3425);
DISPLAY INVISIBLE (2300 3425);
FORCEPROP 1 LAST BODY_TYPE PLUMBING
J 2
(2300 3375);
DISPLAY 1.234043 (2300 3375);
PAINT GREEN (2300 3375);
DISPLAY INVISIBLE (2300 3375);
FORCEPROP 1 LAST HDL_TAP TRUE
J 2
(1975 3300);
DISPLAY 1.234043 (1975 3300);
PAINT GREEN (1975 3300);
DISPLAY INVISIBLE (1975 3300);
FORCEPROP 1 LAST PATH I147
J 2
(2302 3425);
DISPLAY 0.872340 (2302 3425);
PAINT GREEN (2302 3425);
DISPLAY INVISIBLE (2302 3425);
FORCEADD TAP..6
R 2
(2300 3525);
FORCEPROP 3 LASTPIN (2250 3525) SIG_NAME M_K_DQS_DP<4>
J 0
(2260 3535);
DISPLAY 0.659574 (2260 3535);
PAINT MONO (2260 3535);
DISPLAY INVISIBLE (2260 3535);
FORCEPROP 1 LASTPIN (2250 3525) BN 4
J 2
(2300 3535);
DISPLAY 0.617021 (2300 3535);
PAINT PINK (2300 3535);
FORCEPROP 2 LAST CDS_LIB mstr_standard
J 0
(2300 3525);
DISPLAY 0.787234 (2300 3525);
PAINT MONO (2300 3525);
DISPLAY INVISIBLE (2300 3525);
FORCEPROP 1 LAST BODY_TYPE PLUMBING
J 2
(2300 3475);
DISPLAY 1.234043 (2300 3475);
PAINT GREEN (2300 3475);
DISPLAY INVISIBLE (2300 3475);
FORCEPROP 1 LAST HDL_TAP TRUE
J 2
(1975 3400);
DISPLAY 1.234043 (1975 3400);
PAINT GREEN (1975 3400);
DISPLAY INVISIBLE (1975 3400);
FORCEPROP 1 LAST PATH I148
J 2
(2302 3525);
DISPLAY 0.872340 (2302 3525);
PAINT GREEN (2302 3525);
DISPLAY INVISIBLE (2302 3525);
FORCEADD TAP..6
R 2
(2300 3625);
FORCEPROP 3 LASTPIN (2250 3625) SIG_NAME M_K_DQS_DP<5>
J 0
(2260 3635);
DISPLAY 0.659574 (2260 3635);
PAINT MONO (2260 3635);
DISPLAY INVISIBLE (2260 3635);
FORCEPROP 1 LASTPIN (2250 3625) BN 5
J 2
(2300 3635);
DISPLAY 0.617021 (2300 3635);
PAINT PINK (2300 3635);
FORCEPROP 2 LAST CDS_LIB mstr_standard
J 0
(2300 3625);
DISPLAY 0.787234 (2300 3625);
PAINT MONO (2300 3625);
DISPLAY INVISIBLE (2300 3625);
FORCEPROP 1 LAST BODY_TYPE PLUMBING
J 2
(2300 3575);
DISPLAY 1.234043 (2300 3575);
PAINT GREEN (2300 3575);
DISPLAY INVISIBLE (2300 3575);
FORCEPROP 1 LAST HDL_TAP TRUE
J 2
(1975 3500);
DISPLAY 1.234043 (1975 3500);
PAINT GREEN (1975 3500);
DISPLAY INVISIBLE (1975 3500);
FORCEPROP 1 LAST PATH I149
J 2
(2302 3625);
DISPLAY 0.872340 (2302 3625);
PAINT GREEN (2302 3625);
DISPLAY INVISIBLE (2302 3625);
FORCEADD OFFPAGE..1
(-2250 2375);
FORCEPROP 2 LAST $XR0 55 
J 0
(-2501 2375);
DISPLAY 0.638298 (-2501 2375);
PAINT MONO (-2501 2375);
FORCEPROP 2 LAST $XR1 83 
J 0
(-2591 2375);
DISPLAY 0.638298 (-2591 2375);
PAINT MONO (-2591 2375);
FORCEPROP 2 LAST $XR2 85 
J 0
(-2681 2375);
DISPLAY 0.638298 (-2681 2375);
PAINT MONO (-2681 2375);
FORCEPROP 2 LAST $XR3 86 
J 0
(-2771 2375);
DISPLAY 0.638298 (-2771 2375);
PAINT MONO (-2771 2375);
FORCEPROP 2 LAST $XR4 87 
J 0
(-2861 2375);
DISPLAY 0.638298 (-2861 2375);
PAINT MONO (-2861 2375);
FORCEPROP 2 LAST $XR5 88 
J 0
(-2951 2375);
DISPLAY 0.638298 (-2951 2375);
PAINT MONO (-2951 2375);
FORCEPROP 2 LAST CDS_LIB mstr_standard
J 0
(-2250 2375);
DISPLAY 0.787234 (-2250 2375);
PAINT MONO (-2250 2375);
DISPLAY INVISIBLE (-2250 2375);
FORCEPROP 1 LAST OFFPAGE TRUE
J 0
(-1925 2250);
DISPLAY 0.936170 (-1925 2250);
PAINT GREEN (-1925 2250);
DISPLAY INVISIBLE (-1925 2250);
FORCEPROP 1 LAST COMMENT_BODY TRUE
J 0
(-2125 2275);
DISPLAY 0.936170 (-2125 2275);
PAINT GREEN (-2125 2275);
DISPLAY INVISIBLE (-2125 2275);
FORCEPROP 2 LAST PATH I15
J 0
(-2500 2425);
DISPLAY 1.021277 (-2500 2425);
PAINT ORANGE (-2500 2425);
DISPLAY INVISIBLE (-2500 2425);
FORCEADD TAP..6
R 2
(2500 3275);
FORCEPROP 3 LASTPIN (2450 3275) SIG_NAME M_K_DQS_DN<2>
J 0
(2460 3285);
DISPLAY 0.659574 (2460 3285);
PAINT MONO (2460 3285);
DISPLAY INVISIBLE (2460 3285);
FORCEPROP 1 LASTPIN (2450 3275) BN 2
J 2
(2500 3285);
DISPLAY 0.617021 (2500 3285);
PAINT PINK (2500 3285);
FORCEPROP 2 LAST CDS_LIB mstr_standard
J 0
(2500 3275);
DISPLAY 0.787234 (2500 3275);
PAINT MONO (2500 3275);
DISPLAY INVISIBLE (2500 3275);
FORCEPROP 1 LAST BODY_TYPE PLUMBING
J 2
(2500 3225);
DISPLAY 1.234043 (2500 3225);
PAINT GREEN (2500 3225);
DISPLAY INVISIBLE (2500 3225);
FORCEPROP 1 LAST HDL_TAP TRUE
J 2
(2175 3150);
DISPLAY 1.234043 (2175 3150);
PAINT GREEN (2175 3150);
DISPLAY INVISIBLE (2175 3150);
FORCEPROP 1 LAST PATH I150
J 2
(2502 3275);
DISPLAY 0.872340 (2502 3275);
PAINT GREEN (2502 3275);
DISPLAY INVISIBLE (2502 3275);
FORCEADD TAP..6
R 2
(2500 3375);
FORCEPROP 3 LASTPIN (2450 3375) SIG_NAME M_K_DQS_DN<3>
J 0
(2460 3385);
DISPLAY 0.659574 (2460 3385);
PAINT MONO (2460 3385);
DISPLAY INVISIBLE (2460 3385);
FORCEPROP 1 LASTPIN (2450 3375) BN 3
J 2
(2500 3385);
DISPLAY 0.617021 (2500 3385);
PAINT PINK (2500 3385);
FORCEPROP 2 LAST CDS_LIB mstr_standard
J 0
(2500 3375);
DISPLAY 0.787234 (2500 3375);
PAINT MONO (2500 3375);
DISPLAY INVISIBLE (2500 3375);
FORCEPROP 1 LAST BODY_TYPE PLUMBING
J 2
(2500 3325);
DISPLAY 1.234043 (2500 3325);
PAINT GREEN (2500 3325);
DISPLAY INVISIBLE (2500 3325);
FORCEPROP 1 LAST HDL_TAP TRUE
J 2
(2175 3250);
DISPLAY 1.234043 (2175 3250);
PAINT GREEN (2175 3250);
DISPLAY INVISIBLE (2175 3250);
FORCEPROP 1 LAST PATH I151
J 2
(2502 3375);
DISPLAY 0.872340 (2502 3375);
PAINT GREEN (2502 3375);
DISPLAY INVISIBLE (2502 3375);
FORCEADD TAP..6
R 2
(2500 3675);
FORCEPROP 3 LASTPIN (2450 3675) SIG_NAME M_K_DQS_DN<6>
J 0
(2460 3685);
DISPLAY 0.659574 (2460 3685);
PAINT MONO (2460 3685);
DISPLAY INVISIBLE (2460 3685);
FORCEPROP 1 LASTPIN (2450 3675) BN 6
J 2
(2500 3685);
DISPLAY 0.617021 (2500 3685);
PAINT PINK (2500 3685);
FORCEPROP 2 LAST CDS_LIB mstr_standard
J 0
(2500 3675);
DISPLAY 0.787234 (2500 3675);
PAINT MONO (2500 3675);
DISPLAY INVISIBLE (2500 3675);
FORCEPROP 1 LAST BODY_TYPE PLUMBING
J 2
(2500 3625);
DISPLAY 1.234043 (2500 3625);
PAINT GREEN (2500 3625);
DISPLAY INVISIBLE (2500 3625);
FORCEPROP 1 LAST HDL_TAP TRUE
J 2
(2175 3550);
DISPLAY 1.234043 (2175 3550);
PAINT GREEN (2175 3550);
DISPLAY INVISIBLE (2175 3550);
FORCEPROP 1 LAST PATH I152
J 2
(2502 3675);
DISPLAY 0.872340 (2502 3675);
PAINT GREEN (2502 3675);
DISPLAY INVISIBLE (2502 3675);
FORCEADD TAP..6
R 2
(2500 3575);
FORCEPROP 3 LASTPIN (2450 3575) SIG_NAME M_K_DQS_DN<5>
J 0
(2460 3585);
DISPLAY 0.659574 (2460 3585);
PAINT MONO (2460 3585);
DISPLAY INVISIBLE (2460 3585);
FORCEPROP 1 LASTPIN (2450 3575) BN 5
J 2
(2500 3585);
DISPLAY 0.617021 (2500 3585);
PAINT PINK (2500 3585);
FORCEPROP 2 LAST CDS_LIB mstr_standard
J 0
(2500 3575);
DISPLAY 0.787234 (2500 3575);
PAINT MONO (2500 3575);
DISPLAY INVISIBLE (2500 3575);
FORCEPROP 1 LAST BODY_TYPE PLUMBING
J 2
(2500 3525);
DISPLAY 1.234043 (2500 3525);
PAINT GREEN (2500 3525);
DISPLAY INVISIBLE (2500 3525);
FORCEPROP 1 LAST HDL_TAP TRUE
J 2
(2175 3450);
DISPLAY 1.234043 (2175 3450);
PAINT GREEN (2175 3450);
DISPLAY INVISIBLE (2175 3450);
FORCEPROP 1 LAST PATH I153
J 2
(2502 3575);
DISPLAY 0.872340 (2502 3575);
PAINT GREEN (2502 3575);
DISPLAY INVISIBLE (2502 3575);
FORCEADD TAP..6
R 2
(2500 3475);
FORCEPROP 3 LASTPIN (2450 3475) SIG_NAME M_K_DQS_DN<4>
J 0
(2460 3485);
DISPLAY 0.659574 (2460 3485);
PAINT MONO (2460 3485);
DISPLAY INVISIBLE (2460 3485);
FORCEPROP 1 LASTPIN (2450 3475) BN 4
J 2
(2500 3485);
DISPLAY 0.617021 (2500 3485);
PAINT PINK (2500 3485);
FORCEPROP 2 LAST CDS_LIB mstr_standard
J 0
(2500 3475);
DISPLAY 0.787234 (2500 3475);
PAINT MONO (2500 3475);
DISPLAY INVISIBLE (2500 3475);
FORCEPROP 1 LAST BODY_TYPE PLUMBING
J 2
(2500 3425);
DISPLAY 1.234043 (2500 3425);
PAINT GREEN (2500 3425);
DISPLAY INVISIBLE (2500 3425);
FORCEPROP 1 LAST HDL_TAP TRUE
J 2
(2175 3350);
DISPLAY 1.234043 (2175 3350);
PAINT GREEN (2175 3350);
DISPLAY INVISIBLE (2175 3350);
FORCEPROP 1 LAST PATH I154
J 2
(2502 3475);
DISPLAY 0.872340 (2502 3475);
PAINT GREEN (2502 3475);
DISPLAY INVISIBLE (2502 3475);
FORCEADD GND..1
R 2
(4100 725);
FORCEPROP 3 LASTPIN (4100 775) SIG_NAME GND\g
J 0
(4110 785);
DISPLAY 0.659574 (4110 785);
PAINT MONO (4110 785);
DISPLAY INVISIBLE (4110 785);
FORCEPROP 1 LAST VOLTAGE 0
J 0
(4100 725);
PAINT SKYBLUE (4100 725);
DISPLAY INVISIBLE (4100 725);
FORCEPROP 2 LAST CDS_LIB mstr_symbols
J 0
(4100 725);
DISPLAY 0.787234 (4100 725);
PAINT MONO (4100 725);
DISPLAY INVISIBLE (4100 725);
FORCEPROP 1 LAST SIZE 1B
J 2
(4025 675);
DISPLAY 1.170213 (4025 675);
PAINT GREEN (4025 675);
DISPLAY INVISIBLE (4025 675);
FORCEPROP 2 LAST BOM_COST MEM
J 0
(4100 730);
PAINT ORANGE (4100 730);
DISPLAY INVISIBLE (4100 730);
FORCEPROP 1 LAST BODY_TYPE PLUMBING
J 2
(4145 682);
DISPLAY 0.340426 (4145 682);
PAINT GREEN (4145 682);
DISPLAY INVISIBLE (4145 682);
FORCEPROP 1 LAST PATH I155
J 2
(4025 725);
DISPLAY 0.872340 (4025 725);
PAINT AQUA (4025 725);
DISPLAY INVISIBLE (4025 725);
FORCEPROP 2 LAST ROOM DDR4_CH_C
J 0
(4100 730);
PAINT ORANGE (4100 730);
DISPLAY INVISIBLE (4100 730);
FORCEPROP 1 LAST HDL_POWER GND
J 2
(4100 875);
DISPLAY 0.553191 (4100 875);
PAINT GREEN (4100 875);
DISPLAY INVISIBLE (4100 875);
FORCEADD TAP..6
R 2
(2300 3725);
FORCEPROP 3 LASTPIN (2250 3725) SIG_NAME M_K_DQS_DP<6>
J 0
(2260 3735);
DISPLAY 0.659574 (2260 3735);
PAINT MONO (2260 3735);
DISPLAY INVISIBLE (2260 3735);
FORCEPROP 1 LASTPIN (2250 3725) BN 6
J 2
(2300 3735);
DISPLAY 0.617021 (2300 3735);
PAINT PINK (2300 3735);
FORCEPROP 2 LAST CDS_LIB mstr_standard
J 0
(2300 3725);
DISPLAY 0.787234 (2300 3725);
PAINT MONO (2300 3725);
DISPLAY INVISIBLE (2300 3725);
FORCEPROP 1 LAST BODY_TYPE PLUMBING
J 2
(2300 3675);
DISPLAY 1.234043 (2300 3675);
PAINT GREEN (2300 3675);
DISPLAY INVISIBLE (2300 3675);
FORCEPROP 1 LAST HDL_TAP TRUE
J 2
(1975 3600);
DISPLAY 1.234043 (1975 3600);
PAINT GREEN (1975 3600);
DISPLAY INVISIBLE (1975 3600);
FORCEPROP 1 LAST PATH I156
J 2
(2302 3725);
DISPLAY 0.872340 (2302 3725);
PAINT GREEN (2302 3725);
DISPLAY INVISIBLE (2302 3725);
FORCEADD TAP..6
R 2
(2300 3825);
FORCEPROP 3 LASTPIN (2250 3825) SIG_NAME M_K_DQS_DP<7>
J 0
(2260 3835);
DISPLAY 0.659574 (2260 3835);
PAINT MONO (2260 3835);
DISPLAY INVISIBLE (2260 3835);
FORCEPROP 1 LASTPIN (2250 3825) BN 7
J 2
(2300 3835);
DISPLAY 0.617021 (2300 3835);
PAINT PINK (2300 3835);
FORCEPROP 2 LAST CDS_LIB mstr_standard
J 0
(2300 3825);
DISPLAY 0.787234 (2300 3825);
PAINT MONO (2300 3825);
DISPLAY INVISIBLE (2300 3825);
FORCEPROP 1 LAST BODY_TYPE PLUMBING
J 2
(2300 3775);
DISPLAY 1.234043 (2300 3775);
PAINT GREEN (2300 3775);
DISPLAY INVISIBLE (2300 3775);
FORCEPROP 1 LAST HDL_TAP TRUE
J 2
(1975 3700);
DISPLAY 1.234043 (1975 3700);
PAINT GREEN (1975 3700);
DISPLAY INVISIBLE (1975 3700);
FORCEPROP 1 LAST PATH I157
J 2
(2302 3825);
DISPLAY 0.872340 (2302 3825);
PAINT GREEN (2302 3825);
DISPLAY INVISIBLE (2302 3825);
FORCEADD TAP..6
R 2
(2300 3925);
FORCEPROP 3 LASTPIN (2250 3925) SIG_NAME M_K_DQS_DP<8>
J 0
(2260 3935);
DISPLAY 0.659574 (2260 3935);
PAINT MONO (2260 3935);
DISPLAY INVISIBLE (2260 3935);
FORCEPROP 1 LASTPIN (2250 3925) BN 8
J 2
(2300 3935);
DISPLAY 0.617021 (2300 3935);
PAINT PINK (2300 3935);
FORCEPROP 2 LAST CDS_LIB mstr_standard
J 0
(2300 3925);
DISPLAY 0.787234 (2300 3925);
PAINT MONO (2300 3925);
DISPLAY INVISIBLE (2300 3925);
FORCEPROP 1 LAST BODY_TYPE PLUMBING
J 2
(2300 3875);
DISPLAY 1.234043 (2300 3875);
PAINT GREEN (2300 3875);
DISPLAY INVISIBLE (2300 3875);
FORCEPROP 1 LAST HDL_TAP TRUE
J 2
(1975 3800);
DISPLAY 1.234043 (1975 3800);
PAINT GREEN (1975 3800);
DISPLAY INVISIBLE (1975 3800);
FORCEPROP 1 LAST PATH I158
J 2
(2302 3925);
DISPLAY 0.872340 (2302 3925);
PAINT GREEN (2302 3925);
DISPLAY INVISIBLE (2302 3925);
FORCEADD TAP..6
R 2
(2300 4025);
FORCEPROP 3 LASTPIN (2250 4025) SIG_NAME M_K_DQS_DP<9>
J 0
(2260 4035);
DISPLAY 0.659574 (2260 4035);
PAINT MONO (2260 4035);
DISPLAY INVISIBLE (2260 4035);
FORCEPROP 1 LASTPIN (2250 4025) BN 9
J 2
(2300 4035);
DISPLAY 0.617021 (2300 4035);
PAINT PINK (2300 4035);
FORCEPROP 2 LAST CDS_LIB mstr_standard
J 0
(2300 4025);
DISPLAY 0.787234 (2300 4025);
PAINT MONO (2300 4025);
DISPLAY INVISIBLE (2300 4025);
FORCEPROP 1 LAST BODY_TYPE PLUMBING
J 2
(2300 3975);
DISPLAY 1.234043 (2300 3975);
PAINT GREEN (2300 3975);
DISPLAY INVISIBLE (2300 3975);
FORCEPROP 1 LAST HDL_TAP TRUE
J 2
(1975 3900);
DISPLAY 1.234043 (1975 3900);
PAINT GREEN (1975 3900);
DISPLAY INVISIBLE (1975 3900);
FORCEPROP 1 LAST PATH I159
J 2
(2302 4025);
DISPLAY 0.872340 (2302 4025);
PAINT GREEN (2302 4025);
DISPLAY INVISIBLE (2302 4025);
FORCEADD OFFPAGE..1
(-2250 2425);
FORCEPROP 2 LAST $XR0 60 
J 0
(-2501 2425);
DISPLAY 0.638298 (-2501 2425);
PAINT MONO (-2501 2425);
FORCEPROP 2 LAST $XR1 83 
J 0
(-2591 2425);
DISPLAY 0.638298 (-2591 2425);
PAINT MONO (-2591 2425);
FORCEPROP 2 LAST CDS_LIB mstr_standard
J 0
(-2250 2425);
DISPLAY 0.787234 (-2250 2425);
PAINT MONO (-2250 2425);
DISPLAY INVISIBLE (-2250 2425);
FORCEPROP 1 LAST OFFPAGE TRUE
J 0
(-1925 2300);
DISPLAY 0.936170 (-1925 2300);
PAINT GREEN (-1925 2300);
DISPLAY INVISIBLE (-1925 2300);
FORCEPROP 1 LAST COMMENT_BODY TRUE
J 0
(-2125 2325);
DISPLAY 0.936170 (-2125 2325);
PAINT GREEN (-2125 2325);
DISPLAY INVISIBLE (-2125 2325);
FORCEPROP 2 LAST PATH I16
J 0
(-2500 2475);
DISPLAY 1.021277 (-2500 2475);
PAINT ORANGE (-2500 2475);
DISPLAY INVISIBLE (-2500 2475);
FORCEADD TAP..6
R 2
(2300 4225);
FORCEPROP 3 LASTPIN (2250 4225) SIG_NAME M_K_DQS_DP<11>
J 0
(2260 4235);
DISPLAY 0.659574 (2260 4235);
PAINT MONO (2260 4235);
DISPLAY INVISIBLE (2260 4235);
FORCEPROP 1 LASTPIN (2250 4225) BN 11
J 2
(2300 4235);
DISPLAY 0.617021 (2300 4235);
PAINT PINK (2300 4235);
FORCEPROP 2 LAST CDS_LIB mstr_standard
J 0
(2300 4225);
DISPLAY 0.787234 (2300 4225);
PAINT MONO (2300 4225);
DISPLAY INVISIBLE (2300 4225);
FORCEPROP 1 LAST BODY_TYPE PLUMBING
J 2
(2300 4175);
DISPLAY 1.234043 (2300 4175);
PAINT GREEN (2300 4175);
DISPLAY INVISIBLE (2300 4175);
FORCEPROP 1 LAST HDL_TAP TRUE
J 2
(1975 4100);
DISPLAY 1.234043 (1975 4100);
PAINT GREEN (1975 4100);
DISPLAY INVISIBLE (1975 4100);
FORCEPROP 1 LAST PATH I160
J 2
(2302 4225);
DISPLAY 0.872340 (2302 4225);
PAINT GREEN (2302 4225);
DISPLAY INVISIBLE (2302 4225);
FORCEADD TAP..6
R 2
(2300 4125);
FORCEPROP 3 LASTPIN (2250 4125) SIG_NAME M_K_DQS_DP<10>
J 0
(2260 4135);
DISPLAY 0.659574 (2260 4135);
PAINT MONO (2260 4135);
DISPLAY INVISIBLE (2260 4135);
FORCEPROP 1 LASTPIN (2250 4125) BN 10
J 2
(2300 4135);
DISPLAY 0.617021 (2300 4135);
PAINT PINK (2300 4135);
FORCEPROP 2 LAST CDS_LIB mstr_standard
J 0
(2300 4125);
DISPLAY 0.787234 (2300 4125);
PAINT MONO (2300 4125);
DISPLAY INVISIBLE (2300 4125);
FORCEPROP 1 LAST BODY_TYPE PLUMBING
J 2
(2300 4075);
DISPLAY 1.234043 (2300 4075);
PAINT GREEN (2300 4075);
DISPLAY INVISIBLE (2300 4075);
FORCEPROP 1 LAST HDL_TAP TRUE
J 2
(1975 4000);
DISPLAY 1.234043 (1975 4000);
PAINT GREEN (1975 4000);
DISPLAY INVISIBLE (1975 4000);
FORCEPROP 1 LAST PATH I161
J 2
(2302 4125);
DISPLAY 0.872340 (2302 4125);
PAINT GREEN (2302 4125);
DISPLAY INVISIBLE (2302 4125);
FORCEADD TAP..6
R 2
(2500 3975);
FORCEPROP 3 LASTPIN (2450 3975) SIG_NAME M_K_DQS_DN<9>
J 0
(2460 3985);
DISPLAY 0.659574 (2460 3985);
PAINT MONO (2460 3985);
DISPLAY INVISIBLE (2460 3985);
FORCEPROP 1 LASTPIN (2450 3975) BN 9
J 2
(2500 3985);
DISPLAY 0.617021 (2500 3985);
PAINT PINK (2500 3985);
FORCEPROP 2 LAST CDS_LIB mstr_standard
J 0
(2500 3975);
DISPLAY 0.787234 (2500 3975);
PAINT MONO (2500 3975);
DISPLAY INVISIBLE (2500 3975);
FORCEPROP 1 LAST BODY_TYPE PLUMBING
J 2
(2500 3925);
DISPLAY 1.234043 (2500 3925);
PAINT GREEN (2500 3925);
DISPLAY INVISIBLE (2500 3925);
FORCEPROP 1 LAST HDL_TAP TRUE
J 2
(2175 3850);
DISPLAY 1.234043 (2175 3850);
PAINT GREEN (2175 3850);
DISPLAY INVISIBLE (2175 3850);
FORCEPROP 1 LAST PATH I162
J 2
(2502 3975);
DISPLAY 0.872340 (2502 3975);
PAINT GREEN (2502 3975);
DISPLAY INVISIBLE (2502 3975);
FORCEADD TAP..6
R 2
(2500 3775);
FORCEPROP 3 LASTPIN (2450 3775) SIG_NAME M_K_DQS_DN<7>
J 0
(2460 3785);
DISPLAY 0.659574 (2460 3785);
PAINT MONO (2460 3785);
DISPLAY INVISIBLE (2460 3785);
FORCEPROP 1 LASTPIN (2450 3775) BN 7
J 2
(2500 3785);
DISPLAY 0.617021 (2500 3785);
PAINT PINK (2500 3785);
FORCEPROP 2 LAST CDS_LIB mstr_standard
J 0
(2500 3775);
DISPLAY 0.787234 (2500 3775);
PAINT MONO (2500 3775);
DISPLAY INVISIBLE (2500 3775);
FORCEPROP 1 LAST BODY_TYPE PLUMBING
J 2
(2500 3725);
DISPLAY 1.234043 (2500 3725);
PAINT GREEN (2500 3725);
DISPLAY INVISIBLE (2500 3725);
FORCEPROP 1 LAST HDL_TAP TRUE
J 2
(2175 3650);
DISPLAY 1.234043 (2175 3650);
PAINT GREEN (2175 3650);
DISPLAY INVISIBLE (2175 3650);
FORCEPROP 1 LAST PATH I163
J 2
(2502 3775);
DISPLAY 0.872340 (2502 3775);
PAINT GREEN (2502 3775);
DISPLAY INVISIBLE (2502 3775);
FORCEADD TAP..6
R 2
(2500 3875);
FORCEPROP 3 LASTPIN (2450 3875) SIG_NAME M_K_DQS_DN<8>
J 0
(2460 3885);
DISPLAY 0.659574 (2460 3885);
PAINT MONO (2460 3885);
DISPLAY INVISIBLE (2460 3885);
FORCEPROP 1 LASTPIN (2450 3875) BN 8
J 2
(2500 3885);
DISPLAY 0.617021 (2500 3885);
PAINT PINK (2500 3885);
FORCEPROP 2 LAST CDS_LIB mstr_standard
J 0
(2500 3875);
DISPLAY 0.787234 (2500 3875);
PAINT MONO (2500 3875);
DISPLAY INVISIBLE (2500 3875);
FORCEPROP 1 LAST BODY_TYPE PLUMBING
J 2
(2500 3825);
DISPLAY 1.234043 (2500 3825);
PAINT GREEN (2500 3825);
DISPLAY INVISIBLE (2500 3825);
FORCEPROP 1 LAST HDL_TAP TRUE
J 2
(2175 3750);
DISPLAY 1.234043 (2175 3750);
PAINT GREEN (2175 3750);
DISPLAY INVISIBLE (2175 3750);
FORCEPROP 1 LAST PATH I164
J 2
(2502 3875);
DISPLAY 0.872340 (2502 3875);
PAINT GREEN (2502 3875);
DISPLAY INVISIBLE (2502 3875);
FORCEADD TAP..6
R 2
(2500 4175);
FORCEPROP 3 LASTPIN (2450 4175) SIG_NAME M_K_DQS_DN<11>
J 0
(2460 4185);
DISPLAY 0.659574 (2460 4185);
PAINT MONO (2460 4185);
DISPLAY INVISIBLE (2460 4185);
FORCEPROP 1 LASTPIN (2450 4175) BN 11
J 2
(2500 4185);
DISPLAY 0.617021 (2500 4185);
PAINT PINK (2500 4185);
FORCEPROP 2 LAST CDS_LIB mstr_standard
J 0
(2500 4175);
DISPLAY 0.787234 (2500 4175);
PAINT MONO (2500 4175);
DISPLAY INVISIBLE (2500 4175);
FORCEPROP 1 LAST BODY_TYPE PLUMBING
J 2
(2500 4125);
DISPLAY 1.234043 (2500 4125);
PAINT GREEN (2500 4125);
DISPLAY INVISIBLE (2500 4125);
FORCEPROP 1 LAST HDL_TAP TRUE
J 2
(2175 4050);
DISPLAY 1.234043 (2175 4050);
PAINT GREEN (2175 4050);
DISPLAY INVISIBLE (2175 4050);
FORCEPROP 1 LAST PATH I165
J 2
(2502 4175);
DISPLAY 0.872340 (2502 4175);
PAINT GREEN (2502 4175);
DISPLAY INVISIBLE (2502 4175);
FORCEADD TAP..6
R 2
(2500 4075);
FORCEPROP 3 LASTPIN (2450 4075) SIG_NAME M_K_DQS_DN<10>
J 0
(2460 4085);
DISPLAY 0.659574 (2460 4085);
PAINT MONO (2460 4085);
DISPLAY INVISIBLE (2460 4085);
FORCEPROP 1 LASTPIN (2450 4075) BN 10
J 2
(2500 4085);
DISPLAY 0.617021 (2500 4085);
PAINT PINK (2500 4085);
FORCEPROP 2 LAST CDS_LIB mstr_standard
J 0
(2500 4075);
DISPLAY 0.787234 (2500 4075);
PAINT MONO (2500 4075);
DISPLAY INVISIBLE (2500 4075);
FORCEPROP 1 LAST BODY_TYPE PLUMBING
J 2
(2500 4025);
DISPLAY 1.234043 (2500 4025);
PAINT GREEN (2500 4025);
DISPLAY INVISIBLE (2500 4025);
FORCEPROP 1 LAST HDL_TAP TRUE
J 2
(2175 3950);
DISPLAY 1.234043 (2175 3950);
PAINT GREEN (2175 3950);
DISPLAY INVISIBLE (2175 3950);
FORCEPROP 1 LAST PATH I166
J 2
(2502 4075);
DISPLAY 0.872340 (2502 4075);
PAINT GREEN (2502 4075);
DISPLAY INVISIBLE (2502 4075);
FORCEADD TAP..6
R 2
(2300 4325);
FORCEPROP 3 LASTPIN (2250 4325) SIG_NAME M_K_DQS_DP<12>
J 0
(2260 4335);
DISPLAY 0.659574 (2260 4335);
PAINT MONO (2260 4335);
DISPLAY INVISIBLE (2260 4335);
FORCEPROP 1 LASTPIN (2250 4325) BN 12
J 2
(2300 4335);
DISPLAY 0.617021 (2300 4335);
PAINT PINK (2300 4335);
FORCEPROP 2 LAST CDS_LIB mstr_standard
J 0
(2300 4325);
DISPLAY 0.787234 (2300 4325);
PAINT MONO (2300 4325);
DISPLAY INVISIBLE (2300 4325);
FORCEPROP 1 LAST BODY_TYPE PLUMBING
J 2
(2300 4275);
DISPLAY 1.234043 (2300 4275);
PAINT GREEN (2300 4275);
DISPLAY INVISIBLE (2300 4275);
FORCEPROP 1 LAST HDL_TAP TRUE
J 2
(1975 4200);
DISPLAY 1.234043 (1975 4200);
PAINT GREEN (1975 4200);
DISPLAY INVISIBLE (1975 4200);
FORCEPROP 1 LAST PATH I167
J 2
(2302 4325);
DISPLAY 0.872340 (2302 4325);
PAINT GREEN (2302 4325);
DISPLAY INVISIBLE (2302 4325);
FORCEADD TAP..6
R 2
(2300 4425);
FORCEPROP 3 LASTPIN (2250 4425) SIG_NAME M_K_DQS_DP<13>
J 0
(2260 4435);
DISPLAY 0.659574 (2260 4435);
PAINT MONO (2260 4435);
DISPLAY INVISIBLE (2260 4435);
FORCEPROP 1 LASTPIN (2250 4425) BN 13
J 2
(2300 4435);
DISPLAY 0.617021 (2300 4435);
PAINT PINK (2300 4435);
FORCEPROP 2 LAST CDS_LIB mstr_standard
J 0
(2300 4425);
DISPLAY 0.787234 (2300 4425);
PAINT MONO (2300 4425);
DISPLAY INVISIBLE (2300 4425);
FORCEPROP 1 LAST BODY_TYPE PLUMBING
J 2
(2300 4375);
DISPLAY 1.234043 (2300 4375);
PAINT GREEN (2300 4375);
DISPLAY INVISIBLE (2300 4375);
FORCEPROP 1 LAST HDL_TAP TRUE
J 2
(1975 4300);
DISPLAY 1.234043 (1975 4300);
PAINT GREEN (1975 4300);
DISPLAY INVISIBLE (1975 4300);
FORCEPROP 1 LAST PATH I168
J 2
(2302 4425);
DISPLAY 0.872340 (2302 4425);
PAINT GREEN (2302 4425);
DISPLAY INVISIBLE (2302 4425);
FORCEADD TAP..6
R 2
(2300 4525);
FORCEPROP 3 LASTPIN (2250 4525) SIG_NAME M_K_DQS_DP<14>
J 0
(2260 4535);
DISPLAY 0.659574 (2260 4535);
PAINT MONO (2260 4535);
DISPLAY INVISIBLE (2260 4535);
FORCEPROP 1 LASTPIN (2250 4525) BN 14
J 2
(2300 4535);
DISPLAY 0.617021 (2300 4535);
PAINT PINK (2300 4535);
FORCEPROP 2 LAST CDS_LIB mstr_standard
J 0
(2300 4525);
DISPLAY 0.787234 (2300 4525);
PAINT MONO (2300 4525);
DISPLAY INVISIBLE (2300 4525);
FORCEPROP 1 LAST BODY_TYPE PLUMBING
J 2
(2300 4475);
DISPLAY 1.234043 (2300 4475);
PAINT GREEN (2300 4475);
DISPLAY INVISIBLE (2300 4475);
FORCEPROP 1 LAST HDL_TAP TRUE
J 2
(1975 4400);
DISPLAY 1.234043 (1975 4400);
PAINT GREEN (1975 4400);
DISPLAY INVISIBLE (1975 4400);
FORCEPROP 1 LAST PATH I169
J 2
(2302 4525);
DISPLAY 0.872340 (2302 4525);
PAINT GREEN (2302 4525);
DISPLAY INVISIBLE (2302 4525);
FORCEADD OFFPAGE..1
(-2250 2625);
FORCEPROP 2 LAST $XR0 60 
J 0
(-2501 2625);
DISPLAY 0.638298 (-2501 2625);
PAINT MONO (-2501 2625);
FORCEPROP 2 LAST $XR1 83 
J 0
(-2591 2625);
DISPLAY 0.638298 (-2591 2625);
PAINT MONO (-2591 2625);
FORCEPROP 2 LAST CDS_LIB mstr_standard
J 0
(-2250 2625);
DISPLAY 0.787234 (-2250 2625);
PAINT MONO (-2250 2625);
DISPLAY INVISIBLE (-2250 2625);
FORCEPROP 1 LAST OFFPAGE TRUE
J 0
(-1925 2500);
DISPLAY 0.936170 (-1925 2500);
PAINT GREEN (-1925 2500);
DISPLAY INVISIBLE (-1925 2500);
FORCEPROP 1 LAST COMMENT_BODY TRUE
J 0
(-2125 2525);
DISPLAY 0.936170 (-2125 2525);
PAINT GREEN (-2125 2525);
DISPLAY INVISIBLE (-2125 2525);
FORCEPROP 2 LAST PATH I17
J 0
(-2500 2675);
DISPLAY 1.021277 (-2500 2675);
PAINT ORANGE (-2500 2675);
DISPLAY INVISIBLE (-2500 2675);
FORCEADD TAP..6
R 2
(2300 4625);
FORCEPROP 3 LASTPIN (2250 4625) SIG_NAME M_K_DQS_DP<15>
J 0
(2260 4635);
DISPLAY 0.659574 (2260 4635);
PAINT MONO (2260 4635);
DISPLAY INVISIBLE (2260 4635);
FORCEPROP 1 LASTPIN (2250 4625) BN 15
J 2
(2300 4635);
DISPLAY 0.617021 (2300 4635);
PAINT PINK (2300 4635);
FORCEPROP 2 LAST CDS_LIB mstr_standard
J 0
(2300 4625);
DISPLAY 0.787234 (2300 4625);
PAINT MONO (2300 4625);
DISPLAY INVISIBLE (2300 4625);
FORCEPROP 1 LAST BODY_TYPE PLUMBING
J 2
(2300 4575);
DISPLAY 1.234043 (2300 4575);
PAINT GREEN (2300 4575);
DISPLAY INVISIBLE (2300 4575);
FORCEPROP 1 LAST HDL_TAP TRUE
J 2
(1975 4500);
DISPLAY 1.234043 (1975 4500);
PAINT GREEN (1975 4500);
DISPLAY INVISIBLE (1975 4500);
FORCEPROP 1 LAST PATH I170
J 2
(2302 4625);
DISPLAY 0.872340 (2302 4625);
PAINT GREEN (2302 4625);
DISPLAY INVISIBLE (2302 4625);
FORCEADD TAP..6
R 2
(2300 4725);
FORCEPROP 3 LASTPIN (2250 4725) SIG_NAME M_K_DQS_DP<16>
J 0
(2260 4735);
DISPLAY 0.659574 (2260 4735);
PAINT MONO (2260 4735);
DISPLAY INVISIBLE (2260 4735);
FORCEPROP 1 LASTPIN (2250 4725) BN 16
J 2
(2300 4735);
DISPLAY 0.617021 (2300 4735);
PAINT PINK (2300 4735);
FORCEPROP 2 LAST CDS_LIB mstr_standard
J 0
(2300 4725);
DISPLAY 0.787234 (2300 4725);
PAINT MONO (2300 4725);
DISPLAY INVISIBLE (2300 4725);
FORCEPROP 1 LAST BODY_TYPE PLUMBING
J 2
(2300 4675);
DISPLAY 1.234043 (2300 4675);
PAINT GREEN (2300 4675);
DISPLAY INVISIBLE (2300 4675);
FORCEPROP 1 LAST HDL_TAP TRUE
J 2
(1975 4600);
DISPLAY 1.234043 (1975 4600);
PAINT GREEN (1975 4600);
DISPLAY INVISIBLE (1975 4600);
FORCEPROP 1 LAST PATH I171
J 2
(2302 4725);
DISPLAY 0.872340 (2302 4725);
PAINT GREEN (2302 4725);
DISPLAY INVISIBLE (2302 4725);
FORCEADD TAP..6
R 2
(2500 4475);
FORCEPROP 3 LASTPIN (2450 4475) SIG_NAME M_K_DQS_DN<14>
J 0
(2460 4485);
DISPLAY 0.659574 (2460 4485);
PAINT MONO (2460 4485);
DISPLAY INVISIBLE (2460 4485);
FORCEPROP 1 LASTPIN (2450 4475) BN 14
J 2
(2500 4485);
DISPLAY 0.617021 (2500 4485);
PAINT PINK (2500 4485);
FORCEPROP 2 LAST CDS_LIB mstr_standard
J 0
(2500 4475);
DISPLAY 0.787234 (2500 4475);
PAINT MONO (2500 4475);
DISPLAY INVISIBLE (2500 4475);
FORCEPROP 1 LAST BODY_TYPE PLUMBING
J 2
(2500 4425);
DISPLAY 1.234043 (2500 4425);
PAINT GREEN (2500 4425);
DISPLAY INVISIBLE (2500 4425);
FORCEPROP 1 LAST HDL_TAP TRUE
J 2
(2175 4350);
DISPLAY 1.234043 (2175 4350);
PAINT GREEN (2175 4350);
DISPLAY INVISIBLE (2175 4350);
FORCEPROP 1 LAST PATH I172
J 2
(2502 4475);
DISPLAY 0.872340 (2502 4475);
PAINT GREEN (2502 4475);
DISPLAY INVISIBLE (2502 4475);
FORCEADD TAP..6
R 2
(2500 4275);
FORCEPROP 3 LASTPIN (2450 4275) SIG_NAME M_K_DQS_DN<12>
J 0
(2460 4285);
DISPLAY 0.659574 (2460 4285);
PAINT MONO (2460 4285);
DISPLAY INVISIBLE (2460 4285);
FORCEPROP 1 LASTPIN (2450 4275) BN 12
J 2
(2500 4285);
DISPLAY 0.617021 (2500 4285);
PAINT PINK (2500 4285);
FORCEPROP 2 LAST CDS_LIB mstr_standard
J 0
(2500 4275);
DISPLAY 0.787234 (2500 4275);
PAINT MONO (2500 4275);
DISPLAY INVISIBLE (2500 4275);
FORCEPROP 1 LAST BODY_TYPE PLUMBING
J 2
(2500 4225);
DISPLAY 1.234043 (2500 4225);
PAINT GREEN (2500 4225);
DISPLAY INVISIBLE (2500 4225);
FORCEPROP 1 LAST HDL_TAP TRUE
J 2
(2175 4150);
DISPLAY 1.234043 (2175 4150);
PAINT GREEN (2175 4150);
DISPLAY INVISIBLE (2175 4150);
FORCEPROP 1 LAST PATH I173
J 2
(2502 4275);
DISPLAY 0.872340 (2502 4275);
PAINT GREEN (2502 4275);
DISPLAY INVISIBLE (2502 4275);
FORCEADD TAP..6
R 2
(2500 4375);
FORCEPROP 3 LASTPIN (2450 4375) SIG_NAME M_K_DQS_DN<13>
J 0
(2460 4385);
DISPLAY 0.659574 (2460 4385);
PAINT MONO (2460 4385);
DISPLAY INVISIBLE (2460 4385);
FORCEPROP 1 LASTPIN (2450 4375) BN 13
J 2
(2500 4385);
DISPLAY 0.617021 (2500 4385);
PAINT PINK (2500 4385);
FORCEPROP 2 LAST CDS_LIB mstr_standard
J 0
(2500 4375);
DISPLAY 0.787234 (2500 4375);
PAINT MONO (2500 4375);
DISPLAY INVISIBLE (2500 4375);
FORCEPROP 1 LAST BODY_TYPE PLUMBING
J 2
(2500 4325);
DISPLAY 1.234043 (2500 4325);
PAINT GREEN (2500 4325);
DISPLAY INVISIBLE (2500 4325);
FORCEPROP 1 LAST HDL_TAP TRUE
J 2
(2175 4250);
DISPLAY 1.234043 (2175 4250);
PAINT GREEN (2175 4250);
DISPLAY INVISIBLE (2175 4250);
FORCEPROP 1 LAST PATH I174
J 2
(2502 4375);
DISPLAY 0.872340 (2502 4375);
PAINT GREEN (2502 4375);
DISPLAY INVISIBLE (2502 4375);
FORCEADD TAP..6
R 2
(2500 4675);
FORCEPROP 3 LASTPIN (2450 4675) SIG_NAME M_K_DQS_DN<16>
J 0
(2460 4685);
DISPLAY 0.659574 (2460 4685);
PAINT MONO (2460 4685);
DISPLAY INVISIBLE (2460 4685);
FORCEPROP 1 LASTPIN (2450 4675) BN 16
J 2
(2500 4685);
DISPLAY 0.617021 (2500 4685);
PAINT PINK (2500 4685);
FORCEPROP 2 LAST CDS_LIB mstr_standard
J 0
(2500 4675);
DISPLAY 0.787234 (2500 4675);
PAINT MONO (2500 4675);
DISPLAY INVISIBLE (2500 4675);
FORCEPROP 1 LAST BODY_TYPE PLUMBING
J 2
(2500 4625);
DISPLAY 1.234043 (2500 4625);
PAINT GREEN (2500 4625);
DISPLAY INVISIBLE (2500 4625);
FORCEPROP 1 LAST HDL_TAP TRUE
J 2
(2175 4550);
DISPLAY 1.234043 (2175 4550);
PAINT GREEN (2175 4550);
DISPLAY INVISIBLE (2175 4550);
FORCEPROP 1 LAST PATH I175
J 2
(2502 4675);
DISPLAY 0.872340 (2502 4675);
PAINT GREEN (2502 4675);
DISPLAY INVISIBLE (2502 4675);
FORCEADD TAP..6
R 2
(2500 4575);
FORCEPROP 3 LASTPIN (2450 4575) SIG_NAME M_K_DQS_DN<15>
J 0
(2460 4585);
DISPLAY 0.659574 (2460 4585);
PAINT MONO (2460 4585);
DISPLAY INVISIBLE (2460 4585);
FORCEPROP 1 LASTPIN (2450 4575) BN 15
J 2
(2500 4585);
DISPLAY 0.617021 (2500 4585);
PAINT PINK (2500 4585);
FORCEPROP 2 LAST CDS_LIB mstr_standard
J 0
(2500 4575);
DISPLAY 0.787234 (2500 4575);
PAINT MONO (2500 4575);
DISPLAY INVISIBLE (2500 4575);
FORCEPROP 1 LAST BODY_TYPE PLUMBING
J 2
(2500 4525);
DISPLAY 1.234043 (2500 4525);
PAINT GREEN (2500 4525);
DISPLAY INVISIBLE (2500 4525);
FORCEPROP 1 LAST HDL_TAP TRUE
J 2
(2175 4450);
DISPLAY 1.234043 (2175 4450);
PAINT GREEN (2175 4450);
DISPLAY INVISIBLE (2175 4450);
FORCEPROP 1 LAST PATH I176
J 2
(2502 4575);
DISPLAY 0.872340 (2502 4575);
PAINT GREEN (2502 4575);
DISPLAY INVISIBLE (2502 4575);
FORCEADD TAP..6
R 2
(2300 4825);
FORCEPROP 3 LASTPIN (2250 4825) SIG_NAME M_K_DQS_DP<17>
J 0
(2260 4835);
DISPLAY 0.659574 (2260 4835);
PAINT MONO (2260 4835);
DISPLAY INVISIBLE (2260 4835);
FORCEPROP 1 LASTPIN (2250 4825) BN 17
J 2
(2300 4835);
DISPLAY 0.617021 (2300 4835);
PAINT PINK (2300 4835);
FORCEPROP 2 LAST CDS_LIB mstr_standard
J 2
(2300 4825);
DISPLAY 0.787234 (2300 4825);
PAINT MONO (2300 4825);
DISPLAY INVISIBLE (2300 4825);
FORCEPROP 1 LAST BODY_TYPE PLUMBING
J 2
(2300 4775);
DISPLAY 1.234043 (2300 4775);
PAINT GREEN (2300 4775);
DISPLAY INVISIBLE (2300 4775);
FORCEPROP 1 LAST HDL_TAP TRUE
J 2
(1975 4700);
DISPLAY 1.234043 (1975 4700);
PAINT GREEN (1975 4700);
DISPLAY INVISIBLE (1975 4700);
FORCEPROP 1 LAST PATH I177
J 2
(2302 4825);
DISPLAY 0.872340 (2302 4825);
PAINT GREEN (2302 4825);
DISPLAY INVISIBLE (2302 4825);
FORCEADD TAP..6
R 2
(2500 4775);
FORCEPROP 3 LASTPIN (2450 4775) SIG_NAME M_K_DQS_DN<17>
J 0
(2460 4785);
DISPLAY 0.659574 (2460 4785);
PAINT MONO (2460 4785);
DISPLAY INVISIBLE (2460 4785);
FORCEPROP 1 LASTPIN (2450 4775) BN 17
J 2
(2500 4785);
DISPLAY 0.617021 (2500 4785);
PAINT PINK (2500 4785);
FORCEPROP 2 LAST CDS_LIB mstr_standard
J 2
(2500 4775);
DISPLAY 0.787234 (2500 4775);
PAINT MONO (2500 4775);
DISPLAY INVISIBLE (2500 4775);
FORCEPROP 1 LAST BODY_TYPE PLUMBING
J 2
(2500 4725);
DISPLAY 1.234043 (2500 4725);
PAINT GREEN (2500 4725);
DISPLAY INVISIBLE (2500 4725);
FORCEPROP 1 LAST HDL_TAP TRUE
J 2
(2175 4650);
DISPLAY 1.234043 (2175 4650);
PAINT GREEN (2175 4650);
DISPLAY INVISIBLE (2175 4650);
FORCEPROP 1 LAST PATH I178
J 2
(2502 4775);
DISPLAY 0.872340 (2502 4775);
PAINT GREEN (2502 4775);
DISPLAY INVISIBLE (2502 4775);
FORCEADD OFFPAGE..3
(3200 4825);
FORCEPROP 2 LAST $XR0 60 
J 0
(3414 4825);
DISPLAY 0.638298 (3414 4825);
PAINT MONO (3414 4825);
FORCEPROP 2 LAST $XR1 83 
J 0
(3504 4825);
DISPLAY 0.638298 (3504 4825);
PAINT MONO (3504 4825);
FORCEPROP 2 LAST CDS_LIB mstr_standard
J 0
(3200 4825);
DISPLAY 0.787234 (3200 4825);
PAINT MONO (3200 4825);
DISPLAY INVISIBLE (3200 4825);
FORCEPROP 1 LAST OFFPAGE TRUE
J 0
(3525 4700);
DISPLAY 0.936170 (3525 4700);
PAINT GREEN (3525 4700);
DISPLAY INVISIBLE (3525 4700);
FORCEPROP 1 LAST COMMENT_BODY TRUE
J 0
(3150 4725);
DISPLAY 0.936170 (3150 4725);
PAINT GREEN (3150 4725);
DISPLAY INVISIBLE (3150 4725);
FORCEPROP 2 LAST PATH I179
J 0
(3425 4875);
DISPLAY 1.021277 (3425 4875);
PAINT ORANGE (3425 4875);
DISPLAY INVISIBLE (3425 4875);
FORCEADD OFFPAGE..6
(-2250 2475);
FORCEPROP 2 LAST $XR0 60 
J 0
(-2499 2475);
DISPLAY 0.638298 (-2499 2475);
PAINT MONO (-2499 2475);
FORCEPROP 2 LAST $XR1 83 
J 0
(-2589 2475);
DISPLAY 0.638298 (-2589 2475);
PAINT MONO (-2589 2475);
FORCEPROP 2 LAST CDS_LIB mstr_standard
J 0
(-2250 2475);
DISPLAY 0.787234 (-2250 2475);
PAINT MONO (-2250 2475);
DISPLAY INVISIBLE (-2250 2475);
FORCEPROP 1 LAST OFFPAGE TRUE
J 0
(-1925 2350);
DISPLAY 0.936170 (-1925 2350);
PAINT GREEN (-1925 2350);
DISPLAY INVISIBLE (-1925 2350);
FORCEPROP 1 LAST COMMENT_BODY TRUE
J 0
(-2150 2400);
DISPLAY 0.936170 (-2150 2400);
PAINT GREEN (-2150 2400);
DISPLAY INVISIBLE (-2150 2400);
FORCEPROP 2 LAST PATH I18
J 0
(-2475 2525);
DISPLAY 1.021277 (-2475 2525);
PAINT ORANGE (-2475 2525);
DISPLAY INVISIBLE (-2475 2525);
FORCEADD OFFPAGE..3
(3200 4875);
FORCEPROP 2 LAST $XR0 60 
J 0
(3414 4875);
DISPLAY 0.638298 (3414 4875);
PAINT MONO (3414 4875);
FORCEPROP 2 LAST $XR1 83 
J 0
(3504 4875);
DISPLAY 0.638298 (3504 4875);
PAINT MONO (3504 4875);
FORCEPROP 2 LAST CDS_LIB mstr_standard
J 0
(3200 4875);
DISPLAY 0.787234 (3200 4875);
PAINT MONO (3200 4875);
DISPLAY INVISIBLE (3200 4875);
FORCEPROP 1 LAST OFFPAGE TRUE
J 0
(3525 4750);
DISPLAY 0.936170 (3525 4750);
PAINT GREEN (3525 4750);
DISPLAY INVISIBLE (3525 4750);
FORCEPROP 1 LAST COMMENT_BODY TRUE
J 0
(3150 4775);
DISPLAY 0.936170 (3150 4775);
PAINT GREEN (3150 4775);
DISPLAY INVISIBLE (3150 4775);
FORCEPROP 2 LAST PATH I180
J 0
(3425 4925);
DISPLAY 1.021277 (3425 4925);
PAINT ORANGE (3425 4925);
DISPLAY INVISIBLE (3425 4925);
FORCEADD P12V_NVDIMM_KLM..1
(2150 2800);
FORCEPROP 3 LASTPIN (2150 2750) SIG_NAME P12V_NVDIMM_KLM\g
J 0
(2160 2760);
DISPLAY 0.659574 (2160 2760);
PAINT MONO (2160 2760);
DISPLAY INVISIBLE (2160 2760);
FORCEPROP 1 LAST VOLTAGE 12.0
J 0
(2105 2757);
DISPLAY 0.340426 (2105 2757);
PAINT SKYBLUE (2105 2757);
DISPLAY INVISIBLE (2105 2757);
FORCEPROP 2 LAST CDS_LIB mstr_symbols
J 0
(2150 2800);
PAINT ORANGE (2150 2800);
DISPLAY INVISIBLE (2150 2800);
FORCEPROP 1 LAST BODY_TYPE PLUMBING
J 0
(2105 2757);
DISPLAY 0.340426 (2105 2757);
PAINT GREEN (2105 2757);
DISPLAY INVISIBLE (2105 2757);
FORCEPROP 1 LAST PATH I181
J 0
(2200 2825);
DISPLAY 0.872340 (2200 2825);
PAINT AQUA (2200 2825);
DISPLAY INVISIBLE (2200 2825);
FORCEPROP 1 LAST HDL_POWER P12V_NVDIMM_KLM
J 1
(2150 2850);
DISPLAY 0.872340 (2150 2850);
PAINT GREEN (2150 2850);
DISPLAY INVISIBLE (2150 2850);
FORCEADD TAP..6
(-1600 2125);
FORCEPROP 3 LASTPIN (-1550 2125) SIG_NAME M_K_ECC<1>
J 0
(-1540 2135);
DISPLAY 0.659574 (-1540 2135);
PAINT MONO (-1540 2135);
DISPLAY INVISIBLE (-1540 2135);
FORCEPROP 1 LASTPIN (-1550 2125) BN 1
J 0
(-1600 2135);
DISPLAY 0.617021 (-1600 2135);
PAINT PINK (-1600 2135);
FORCEPROP 2 LAST CDS_LIB mstr_standard
J 0
(-1600 2125);
DISPLAY 0.787234 (-1600 2125);
PAINT MONO (-1600 2125);
DISPLAY INVISIBLE (-1600 2125);
FORCEPROP 1 LAST BODY_TYPE PLUMBING
J 0
(-1600 2075);
DISPLAY 1.234043 (-1600 2075);
PAINT GREEN (-1600 2075);
DISPLAY INVISIBLE (-1600 2075);
FORCEPROP 1 LAST HDL_TAP TRUE
J 0
(-1275 2000);
DISPLAY 1.234043 (-1275 2000);
PAINT GREEN (-1275 2000);
DISPLAY INVISIBLE (-1275 2000);
FORCEPROP 1 LAST PATH I19
J 0
(-1602 2125);
DISPLAY 0.872340 (-1602 2125);
PAINT GREEN (-1602 2125);
DISPLAY INVISIBLE (-1602 2125);
FORCEADD OFFPAGE..1
(-3150 1325);
FORCEPROP 2 LAST $XR0 100 
J 0
(-3402 1325);
DISPLAY 0.638298 (-3402 1325);
PAINT MONO (-3402 1325);
FORCEPROP 2 LAST $XR1 83 
J 0
(-3492 1325);
DISPLAY 0.638298 (-3492 1325);
PAINT MONO (-3492 1325);
FORCEPROP 2 LAST CDS_LIB mstr_standard
J 0
(-3150 1325);
DISPLAY 0.787234 (-3150 1325);
PAINT MONO (-3150 1325);
DISPLAY INVISIBLE (-3150 1325);
FORCEPROP 1 LAST OFFPAGE TRUE
J 0
(-2825 1200);
DISPLAY 0.936170 (-2825 1200);
PAINT GREEN (-2825 1200);
DISPLAY INVISIBLE (-2825 1200);
FORCEPROP 1 LAST COMMENT_BODY TRUE
J 0
(-3025 1225);
DISPLAY 0.936170 (-3025 1225);
PAINT GREEN (-3025 1225);
DISPLAY INVISIBLE (-3025 1225);
FORCEPROP 2 LAST PATH I2
J 0
(-3350 1375);
DISPLAY 1.021277 (-3350 1375);
PAINT ORANGE (-3350 1375);
DISPLAY INVISIBLE (-3350 1375);
FORCEADD TAP..6
(-1600 2075);
FORCEPROP 3 LASTPIN (-1550 2075) SIG_NAME M_K_ECC<0>
J 0
(-1540 2085);
DISPLAY 0.659574 (-1540 2085);
PAINT MONO (-1540 2085);
DISPLAY INVISIBLE (-1540 2085);
FORCEPROP 1 LASTPIN (-1550 2075) BN 0
J 0
(-1600 2085);
DISPLAY 0.617021 (-1600 2085);
PAINT PINK (-1600 2085);
FORCEPROP 2 LAST CDS_LIB mstr_standard
J 0
(-1600 2075);
DISPLAY 0.787234 (-1600 2075);
PAINT MONO (-1600 2075);
DISPLAY INVISIBLE (-1600 2075);
FORCEPROP 1 LAST BODY_TYPE PLUMBING
J 0
(-1600 2025);
DISPLAY 1.234043 (-1600 2025);
PAINT GREEN (-1600 2025);
DISPLAY INVISIBLE (-1600 2025);
FORCEPROP 1 LAST HDL_TAP TRUE
J 0
(-1275 1950);
DISPLAY 1.234043 (-1275 1950);
PAINT GREEN (-1275 1950);
DISPLAY INVISIBLE (-1275 1950);
FORCEPROP 1 LAST PATH I20
J 0
(-1602 2075);
DISPLAY 0.872340 (-1602 2075);
PAINT GREEN (-1602 2075);
DISPLAY INVISIBLE (-1602 2075);
FORCEADD TAP..6
(-1600 2175);
FORCEPROP 3 LASTPIN (-1550 2175) SIG_NAME M_K_ECC<2>
J 0
(-1540 2185);
DISPLAY 0.659574 (-1540 2185);
PAINT MONO (-1540 2185);
DISPLAY INVISIBLE (-1540 2185);
FORCEPROP 1 LASTPIN (-1550 2175) BN 2
J 0
(-1600 2185);
DISPLAY 0.617021 (-1600 2185);
PAINT PINK (-1600 2185);
FORCEPROP 2 LAST CDS_LIB mstr_standard
J 0
(-1600 2175);
DISPLAY 0.787234 (-1600 2175);
PAINT MONO (-1600 2175);
DISPLAY INVISIBLE (-1600 2175);
FORCEPROP 1 LAST BODY_TYPE PLUMBING
J 0
(-1600 2125);
DISPLAY 1.234043 (-1600 2125);
PAINT GREEN (-1600 2125);
DISPLAY INVISIBLE (-1600 2125);
FORCEPROP 1 LAST HDL_TAP TRUE
J 0
(-1275 2050);
DISPLAY 1.234043 (-1275 2050);
PAINT GREEN (-1275 2050);
DISPLAY INVISIBLE (-1275 2050);
FORCEPROP 1 LAST PATH I21
J 0
(-1602 2175);
DISPLAY 0.872340 (-1602 2175);
PAINT GREEN (-1602 2175);
DISPLAY INVISIBLE (-1602 2175);
FORCEADD TAP..6
(-1600 2225);
FORCEPROP 3 LASTPIN (-1550 2225) SIG_NAME M_K_ECC<3>
J 0
(-1540 2235);
DISPLAY 0.659574 (-1540 2235);
PAINT MONO (-1540 2235);
DISPLAY INVISIBLE (-1540 2235);
FORCEPROP 1 LASTPIN (-1550 2225) BN 3
J 0
(-1600 2235);
DISPLAY 0.617021 (-1600 2235);
PAINT PINK (-1600 2235);
FORCEPROP 2 LAST CDS_LIB mstr_standard
J 0
(-1600 2225);
DISPLAY 0.787234 (-1600 2225);
PAINT MONO (-1600 2225);
DISPLAY INVISIBLE (-1600 2225);
FORCEPROP 1 LAST BODY_TYPE PLUMBING
J 0
(-1600 2175);
DISPLAY 1.234043 (-1600 2175);
PAINT GREEN (-1600 2175);
DISPLAY INVISIBLE (-1600 2175);
FORCEPROP 1 LAST HDL_TAP TRUE
J 0
(-1275 2100);
DISPLAY 1.234043 (-1275 2100);
PAINT GREEN (-1275 2100);
DISPLAY INVISIBLE (-1275 2100);
FORCEPROP 1 LAST PATH I22
J 0
(-1602 2225);
DISPLAY 0.872340 (-1602 2225);
PAINT GREEN (-1602 2225);
DISPLAY INVISIBLE (-1602 2225);
FORCEADD TAP..6
(-1600 2275);
FORCEPROP 3 LASTPIN (-1550 2275) SIG_NAME M_K_ECC<4>
J 0
(-1540 2285);
DISPLAY 0.659574 (-1540 2285);
PAINT MONO (-1540 2285);
DISPLAY INVISIBLE (-1540 2285);
FORCEPROP 1 LASTPIN (-1550 2275) BN 4
J 0
(-1600 2285);
DISPLAY 0.617021 (-1600 2285);
PAINT PINK (-1600 2285);
FORCEPROP 2 LAST CDS_LIB mstr_standard
J 0
(-1600 2275);
DISPLAY 0.787234 (-1600 2275);
PAINT MONO (-1600 2275);
DISPLAY INVISIBLE (-1600 2275);
FORCEPROP 1 LAST BODY_TYPE PLUMBING
J 0
(-1600 2225);
DISPLAY 1.234043 (-1600 2225);
PAINT GREEN (-1600 2225);
DISPLAY INVISIBLE (-1600 2225);
FORCEPROP 1 LAST HDL_TAP TRUE
J 0
(-1275 2150);
DISPLAY 1.234043 (-1275 2150);
PAINT GREEN (-1275 2150);
DISPLAY INVISIBLE (-1275 2150);
FORCEPROP 1 LAST PATH I23
J 0
(-1602 2275);
DISPLAY 0.872340 (-1602 2275);
PAINT GREEN (-1602 2275);
DISPLAY INVISIBLE (-1602 2275);
FORCEADD TAP..6
(-1600 2375);
FORCEPROP 3 LASTPIN (-1550 2375) SIG_NAME M_K_ECC<6>
J 0
(-1540 2385);
DISPLAY 0.659574 (-1540 2385);
PAINT MONO (-1540 2385);
DISPLAY INVISIBLE (-1540 2385);
FORCEPROP 1 LASTPIN (-1550 2375) BN 6
J 0
(-1600 2385);
DISPLAY 0.617021 (-1600 2385);
PAINT PINK (-1600 2385);
FORCEPROP 2 LAST CDS_LIB mstr_standard
J 0
(-1600 2375);
DISPLAY 0.787234 (-1600 2375);
PAINT MONO (-1600 2375);
DISPLAY INVISIBLE (-1600 2375);
FORCEPROP 1 LAST BODY_TYPE PLUMBING
J 0
(-1600 2325);
DISPLAY 1.234043 (-1600 2325);
PAINT GREEN (-1600 2325);
DISPLAY INVISIBLE (-1600 2325);
FORCEPROP 1 LAST HDL_TAP TRUE
J 0
(-1275 2250);
DISPLAY 1.234043 (-1275 2250);
PAINT GREEN (-1275 2250);
DISPLAY INVISIBLE (-1275 2250);
FORCEPROP 1 LAST PATH I24
J 0
(-1602 2375);
DISPLAY 0.872340 (-1602 2375);
PAINT GREEN (-1602 2375);
DISPLAY INVISIBLE (-1602 2375);
FORCEADD TAP..6
(-1600 2325);
FORCEPROP 3 LASTPIN (-1550 2325) SIG_NAME M_K_ECC<5>
J 0
(-1540 2335);
DISPLAY 0.659574 (-1540 2335);
PAINT MONO (-1540 2335);
DISPLAY INVISIBLE (-1540 2335);
FORCEPROP 1 LASTPIN (-1550 2325) BN 5
J 0
(-1600 2335);
DISPLAY 0.617021 (-1600 2335);
PAINT PINK (-1600 2335);
FORCEPROP 2 LAST CDS_LIB mstr_standard
J 0
(-1600 2325);
DISPLAY 0.787234 (-1600 2325);
PAINT MONO (-1600 2325);
DISPLAY INVISIBLE (-1600 2325);
FORCEPROP 1 LAST BODY_TYPE PLUMBING
J 0
(-1600 2275);
DISPLAY 1.234043 (-1600 2275);
PAINT GREEN (-1600 2275);
DISPLAY INVISIBLE (-1600 2275);
FORCEPROP 1 LAST HDL_TAP TRUE
J 0
(-1275 2200);
DISPLAY 1.234043 (-1275 2200);
PAINT GREEN (-1275 2200);
DISPLAY INVISIBLE (-1275 2200);
FORCEPROP 1 LAST PATH I25
J 0
(-1602 2325);
DISPLAY 0.872340 (-1602 2325);
PAINT GREEN (-1602 2325);
DISPLAY INVISIBLE (-1602 2325);
FORCEADD TAP..6
(-1600 2425);
FORCEPROP 3 LASTPIN (-1550 2425) SIG_NAME M_K_ECC<7>
J 0
(-1540 2435);
DISPLAY 0.659574 (-1540 2435);
PAINT MONO (-1540 2435);
DISPLAY INVISIBLE (-1540 2435);
FORCEPROP 1 LASTPIN (-1550 2425) BN 7
J 0
(-1600 2435);
DISPLAY 0.617021 (-1600 2435);
PAINT PINK (-1600 2435);
FORCEPROP 2 LAST CDS_LIB mstr_standard
J 0
(-1600 2425);
DISPLAY 0.787234 (-1600 2425);
PAINT MONO (-1600 2425);
DISPLAY INVISIBLE (-1600 2425);
FORCEPROP 1 LAST BODY_TYPE PLUMBING
J 0
(-1600 2375);
DISPLAY 1.234043 (-1600 2375);
PAINT GREEN (-1600 2375);
DISPLAY INVISIBLE (-1600 2375);
FORCEPROP 1 LAST HDL_TAP TRUE
J 0
(-1275 2300);
DISPLAY 1.234043 (-1275 2300);
PAINT GREEN (-1275 2300);
DISPLAY INVISIBLE (-1275 2300);
FORCEPROP 1 LAST PATH I26
J 0
(-1602 2425);
DISPLAY 0.872340 (-1602 2425);
PAINT GREEN (-1602 2425);
DISPLAY INVISIBLE (-1602 2425);
FORCEADD TAP..6
(-1600 2525);
FORCEPROP 3 LASTPIN (-1550 2525) SIG_NAME M_K_ODT<2>
J 0
(-1540 2535);
DISPLAY 0.659574 (-1540 2535);
PAINT MONO (-1540 2535);
DISPLAY INVISIBLE (-1540 2535);
FORCEPROP 1 LASTPIN (-1550 2525) BN 2
J 0
(-1600 2535);
DISPLAY 0.617021 (-1600 2535);
PAINT PINK (-1600 2535);
FORCEPROP 2 LAST CDS_LIB mstr_standard
J 0
(-1600 2525);
DISPLAY 0.787234 (-1600 2525);
PAINT MONO (-1600 2525);
DISPLAY INVISIBLE (-1600 2525);
FORCEPROP 1 LAST BODY_TYPE PLUMBING
J 0
(-1600 2475);
DISPLAY 1.234043 (-1600 2475);
PAINT GREEN (-1600 2475);
DISPLAY INVISIBLE (-1600 2475);
FORCEPROP 1 LAST HDL_TAP TRUE
J 0
(-1275 2400);
DISPLAY 1.234043 (-1275 2400);
PAINT GREEN (-1275 2400);
DISPLAY INVISIBLE (-1275 2400);
FORCEPROP 1 LAST PATH I27
J 0
(-1602 2525);
DISPLAY 0.872340 (-1602 2525);
PAINT GREEN (-1602 2525);
DISPLAY INVISIBLE (-1602 2525);
FORCEADD TAP..6
(-1600 2575);
FORCEPROP 3 LASTPIN (-1550 2575) SIG_NAME M_K_ODT<3>
J 0
(-1540 2585);
DISPLAY 0.659574 (-1540 2585);
PAINT MONO (-1540 2585);
DISPLAY INVISIBLE (-1540 2585);
FORCEPROP 1 LASTPIN (-1550 2575) BN 3
J 0
(-1600 2585);
DISPLAY 0.617021 (-1600 2585);
PAINT PINK (-1600 2585);
FORCEPROP 2 LAST CDS_LIB mstr_standard
J 0
(-1600 2575);
DISPLAY 0.787234 (-1600 2575);
PAINT MONO (-1600 2575);
DISPLAY INVISIBLE (-1600 2575);
FORCEPROP 1 LAST BODY_TYPE PLUMBING
J 0
(-1600 2525);
DISPLAY 1.234043 (-1600 2525);
PAINT GREEN (-1600 2525);
DISPLAY INVISIBLE (-1600 2525);
FORCEPROP 1 LAST HDL_TAP TRUE
J 0
(-1275 2450);
DISPLAY 1.234043 (-1275 2450);
PAINT GREEN (-1275 2450);
DISPLAY INVISIBLE (-1275 2450);
FORCEPROP 1 LAST PATH I28
J 0
(-1602 2575);
DISPLAY 0.872340 (-1602 2575);
PAINT GREEN (-1602 2575);
DISPLAY INVISIBLE (-1602 2575);
FORCEADD TAP..6
(-1600 2675);
FORCEPROP 3 LASTPIN (-1550 2675) SIG_NAME M_K_CKE<2>
J 0
(-1540 2685);
DISPLAY 0.659574 (-1540 2685);
PAINT MONO (-1540 2685);
DISPLAY INVISIBLE (-1540 2685);
FORCEPROP 1 LASTPIN (-1550 2675) BN 2
J 0
(-1600 2685);
DISPLAY 0.617021 (-1600 2685);
PAINT PINK (-1600 2685);
FORCEPROP 2 LAST CDS_LIB mstr_standard
J 0
(-1600 2675);
DISPLAY 0.787234 (-1600 2675);
PAINT MONO (-1600 2675);
DISPLAY INVISIBLE (-1600 2675);
FORCEPROP 1 LAST BODY_TYPE PLUMBING
J 0
(-1600 2625);
DISPLAY 1.234043 (-1600 2625);
PAINT GREEN (-1600 2625);
DISPLAY INVISIBLE (-1600 2625);
FORCEPROP 1 LAST HDL_TAP TRUE
J 0
(-1275 2550);
DISPLAY 1.234043 (-1275 2550);
PAINT GREEN (-1275 2550);
DISPLAY INVISIBLE (-1275 2550);
FORCEPROP 1 LAST PATH I29
J 0
(-1602 2675);
DISPLAY 0.872340 (-1602 2675);
PAINT GREEN (-1602 2675);
DISPLAY INVISIBLE (-1602 2675);
FORCEADD GND..1
(-3000 875);
FORCEPROP 3 LASTPIN (-3000 925) SIG_NAME GND\g
J 0
(-2990 935);
DISPLAY 0.659574 (-2990 935);
PAINT MONO (-2990 935);
DISPLAY INVISIBLE (-2990 935);
FORCEPROP 1 LAST VOLTAGE 0
J 0
(-3000 875);
PAINT SKYBLUE (-3000 875);
DISPLAY INVISIBLE (-3000 875);
FORCEPROP 2 LAST CDS_LIB mstr_symbols
J 0
(-3000 875);
PAINT ORANGE (-3000 875);
DISPLAY INVISIBLE (-3000 875);
FORCEPROP 1 LAST SIZE 1B
J 0
(-2925 825);
DISPLAY 1.787234 (-2925 825);
PAINT GREEN (-2925 825);
DISPLAY INVISIBLE (-2925 825);
FORCEPROP 2 LAST BOM_COST MEM
J 0
(-3000 880);
PAINT ORANGE (-3000 880);
DISPLAY INVISIBLE (-3000 880);
FORCEPROP 1 LAST BODY_TYPE PLUMBING
J 0
(-3045 832);
DISPLAY 0.340426 (-3045 832);
PAINT GREEN (-3045 832);
DISPLAY INVISIBLE (-3045 832);
FORCEPROP 1 LAST PATH I3
J 0
(-2925 875);
DISPLAY 0.872340 (-2925 875);
PAINT AQUA (-2925 875);
DISPLAY INVISIBLE (-2925 875);
FORCEPROP 2 LAST ROOM DDR4_CH_C
J 0
(-3000 880);
PAINT ORANGE (-3000 880);
DISPLAY INVISIBLE (-3000 880);
FORCEPROP 1 LAST HDL_POWER GND
J 0
(-3000 1025);
DISPLAY 1.404255 (-3000 1025);
PAINT GREEN (-3000 1025);
DISPLAY INVISIBLE (-3000 1025);
FORCEADD OFFPAGE..1
(-2250 2775);
FORCEPROP 2 LAST $XR0 60 
J 0
(-2501 2775);
DISPLAY 0.638298 (-2501 2775);
PAINT MONO (-2501 2775);
FORCEPROP 2 LAST $XR1 83 
J 0
(-2591 2775);
DISPLAY 0.638298 (-2591 2775);
PAINT MONO (-2591 2775);
FORCEPROP 2 LAST CDS_LIB mstr_standard
J 0
(-2250 2775);
DISPLAY 0.787234 (-2250 2775);
PAINT MONO (-2250 2775);
DISPLAY INVISIBLE (-2250 2775);
FORCEPROP 1 LAST OFFPAGE TRUE
J 0
(-1925 2650);
DISPLAY 0.936170 (-1925 2650);
PAINT GREEN (-1925 2650);
DISPLAY INVISIBLE (-1925 2650);
FORCEPROP 1 LAST COMMENT_BODY TRUE
J 0
(-2125 2675);
DISPLAY 0.936170 (-2125 2675);
PAINT GREEN (-2125 2675);
DISPLAY INVISIBLE (-2125 2675);
FORCEPROP 2 LAST PATH I30
J 0
(-2500 2825);
DISPLAY 1.021277 (-2500 2825);
PAINT ORANGE (-2500 2825);
DISPLAY INVISIBLE (-2500 2825);
FORCEADD OFFPAGE..1
(-2250 3025);
FORCEPROP 2 LAST $XR0 60 
J 0
(-2501 3025);
DISPLAY 0.638298 (-2501 3025);
PAINT MONO (-2501 3025);
FORCEPROP 2 LAST $XR1 83 
J 0
(-2591 3025);
DISPLAY 0.638298 (-2591 3025);
PAINT MONO (-2591 3025);
FORCEPROP 2 LAST CDS_LIB mstr_standard
J 0
(-2250 3025);
DISPLAY 0.787234 (-2250 3025);
PAINT MONO (-2250 3025);
DISPLAY INVISIBLE (-2250 3025);
FORCEPROP 1 LAST OFFPAGE TRUE
J 0
(-1925 2900);
DISPLAY 0.936170 (-1925 2900);
PAINT GREEN (-1925 2900);
DISPLAY INVISIBLE (-1925 2900);
FORCEPROP 1 LAST COMMENT_BODY TRUE
J 0
(-2125 2925);
DISPLAY 0.936170 (-2125 2925);
PAINT GREEN (-2125 2925);
DISPLAY INVISIBLE (-2125 2925);
FORCEPROP 2 LAST PATH I31
J 0
(-2500 3075);
DISPLAY 1.021277 (-2500 3075);
PAINT ORANGE (-2500 3075);
DISPLAY INVISIBLE (-2500 3075);
FORCEADD OFFPAGE..1
(-2250 3075);
FORCEPROP 2 LAST $XR0 60 
J 0
(-2501 3075);
DISPLAY 0.638298 (-2501 3075);
PAINT MONO (-2501 3075);
FORCEPROP 2 LAST $XR1 83 
J 0
(-2591 3075);
DISPLAY 0.638298 (-2591 3075);
PAINT MONO (-2591 3075);
FORCEPROP 2 LAST CDS_LIB mstr_standard
J 0
(-2250 3075);
DISPLAY 0.787234 (-2250 3075);
PAINT MONO (-2250 3075);
DISPLAY INVISIBLE (-2250 3075);
FORCEPROP 1 LAST OFFPAGE TRUE
J 0
(-1925 2950);
DISPLAY 0.936170 (-1925 2950);
PAINT GREEN (-1925 2950);
DISPLAY INVISIBLE (-1925 2950);
FORCEPROP 1 LAST COMMENT_BODY TRUE
J 0
(-2125 2975);
DISPLAY 0.936170 (-2125 2975);
PAINT GREEN (-2125 2975);
DISPLAY INVISIBLE (-2125 2975);
FORCEPROP 2 LAST PATH I32
J 0
(-2500 3125);
DISPLAY 1.021277 (-2500 3125);
PAINT ORANGE (-2500 3125);
DISPLAY INVISIBLE (-2500 3125);
FORCEADD TAP..6
(-2100 3125);
FORCEPROP 3 LASTPIN (-2050 3125) SIG_NAME M_K_CLK_DN<2>
J 0
(-2040 3135);
DISPLAY 0.659574 (-2040 3135);
PAINT MONO (-2040 3135);
DISPLAY INVISIBLE (-2040 3135);
FORCEPROP 1 LASTPIN (-2050 3125) BN 2
J 0
(-2100 3135);
DISPLAY 0.617021 (-2100 3135);
PAINT PINK (-2100 3135);
FORCEPROP 2 LAST CDS_LIB mstr_standard
J 0
(-2100 3125);
DISPLAY 0.787234 (-2100 3125);
PAINT MONO (-2100 3125);
DISPLAY INVISIBLE (-2100 3125);
FORCEPROP 1 LAST BODY_TYPE PLUMBING
J 0
(-2100 3075);
DISPLAY 1.234043 (-2100 3075);
PAINT GREEN (-2100 3075);
DISPLAY INVISIBLE (-2100 3075);
FORCEPROP 1 LAST HDL_TAP TRUE
J 0
(-1775 3000);
DISPLAY 1.234043 (-1775 3000);
PAINT GREEN (-1775 3000);
DISPLAY INVISIBLE (-1775 3000);
FORCEPROP 1 LAST PATH I33
J 0
(-2102 3125);
DISPLAY 0.872340 (-2102 3125);
PAINT GREEN (-2102 3125);
DISPLAY INVISIBLE (-2102 3125);
FORCEADD TAP..6
(-1950 3175);
FORCEPROP 3 LASTPIN (-1900 3175) SIG_NAME M_K_CLK_DP<2>
J 0
(-1890 3185);
DISPLAY 0.659574 (-1890 3185);
PAINT MONO (-1890 3185);
DISPLAY INVISIBLE (-1890 3185);
FORCEPROP 1 LASTPIN (-1900 3175) BN 2
J 0
(-1950 3185);
DISPLAY 0.617021 (-1950 3185);
PAINT PINK (-1950 3185);
FORCEPROP 2 LAST CDS_LIB mstr_standard
J 0
(-1950 3175);
DISPLAY 0.787234 (-1950 3175);
PAINT MONO (-1950 3175);
DISPLAY INVISIBLE (-1950 3175);
FORCEPROP 1 LAST BODY_TYPE PLUMBING
J 0
(-1950 3125);
DISPLAY 1.234043 (-1950 3125);
PAINT GREEN (-1950 3125);
DISPLAY INVISIBLE (-1950 3125);
FORCEPROP 1 LAST HDL_TAP TRUE
J 0
(-1625 3050);
DISPLAY 1.234043 (-1625 3050);
PAINT GREEN (-1625 3050);
DISPLAY INVISIBLE (-1625 3050);
FORCEPROP 1 LAST PATH I34
J 0
(-1952 3175);
DISPLAY 0.872340 (-1952 3175);
PAINT GREEN (-1952 3175);
DISPLAY INVISIBLE (-1952 3175);
FORCEADD OFFPAGE..1
(-2250 3475);
FORCEPROP 2 LAST $XR0 60 
J 0
(-2501 3475);
DISPLAY 0.638298 (-2501 3475);
PAINT MONO (-2501 3475);
FORCEPROP 2 LAST $XR1 83 
J 0
(-2591 3475);
DISPLAY 0.638298 (-2591 3475);
PAINT MONO (-2591 3475);
FORCEPROP 2 LAST CDS_LIB mstr_standard
J 0
(-2250 3475);
DISPLAY 0.787234 (-2250 3475);
PAINT MONO (-2250 3475);
DISPLAY INVISIBLE (-2250 3475);
FORCEPROP 1 LAST OFFPAGE TRUE
J 0
(-1925 3350);
DISPLAY 0.936170 (-1925 3350);
PAINT GREEN (-1925 3350);
DISPLAY INVISIBLE (-1925 3350);
FORCEPROP 1 LAST COMMENT_BODY TRUE
J 0
(-2125 3375);
DISPLAY 0.936170 (-2125 3375);
PAINT GREEN (-2125 3375);
DISPLAY INVISIBLE (-2125 3375);
FORCEPROP 2 LAST PATH I35
J 0
(-2500 3525);
DISPLAY 1.021277 (-2500 3525);
PAINT ORANGE (-2500 3525);
DISPLAY INVISIBLE (-2500 3525);
FORCEADD OFFPAGE..1
(-2250 3575);
FORCEPROP 2 LAST $XR0 60 
J 0
(-2501 3575);
DISPLAY 0.638298 (-2501 3575);
PAINT MONO (-2501 3575);
FORCEPROP 2 LAST $XR1 83 
J 0
(-2591 3575);
DISPLAY 0.638298 (-2591 3575);
PAINT MONO (-2591 3575);
FORCEPROP 2 LAST CDS_LIB mstr_standard
J 0
(-2250 3575);
DISPLAY 0.787234 (-2250 3575);
PAINT MONO (-2250 3575);
DISPLAY INVISIBLE (-2250 3575);
FORCEPROP 1 LAST OFFPAGE TRUE
J 0
(-1925 3450);
DISPLAY 0.936170 (-1925 3450);
PAINT GREEN (-1925 3450);
DISPLAY INVISIBLE (-1925 3450);
FORCEPROP 1 LAST COMMENT_BODY TRUE
J 0
(-2125 3475);
DISPLAY 0.936170 (-2125 3475);
PAINT GREEN (-2125 3475);
DISPLAY INVISIBLE (-2125 3475);
FORCEPROP 2 LAST PATH I36
J 0
(-2500 3625);
DISPLAY 1.021277 (-2500 3625);
PAINT ORANGE (-2500 3625);
DISPLAY INVISIBLE (-2500 3625);
FORCEADD TAP..6
(-2100 3225);
FORCEPROP 3 LASTPIN (-2050 3225) SIG_NAME M_K_CLK_DN<3>
J 0
(-2040 3235);
DISPLAY 0.659574 (-2040 3235);
PAINT MONO (-2040 3235);
DISPLAY INVISIBLE (-2040 3235);
FORCEPROP 1 LASTPIN (-2050 3225) BN 3
J 0
(-2102 3233);
DISPLAY 0.617021 (-2102 3233);
PAINT PINK (-2102 3233);
FORCEPROP 2 LAST CDS_LIB mstr_standard
J 0
(-2100 3225);
PAINT MONO (-2100 3225);
DISPLAY INVISIBLE (-2100 3225);
FORCEPROP 1 LAST BODY_TYPE PLUMBING
J 0
(-2100 3175);
DISPLAY 1.234043 (-2100 3175);
PAINT GREEN (-2100 3175);
DISPLAY INVISIBLE (-2100 3175);
FORCEPROP 1 LAST HDL_TAP TRUE
J 0
(-1775 3100);
DISPLAY 1.234043 (-1775 3100);
PAINT GREEN (-1775 3100);
DISPLAY INVISIBLE (-1775 3100);
FORCEPROP 1 LAST PATH I37
J 0
(-2102 3225);
DISPLAY 0.872340 (-2102 3225);
PAINT GREEN (-2102 3225);
DISPLAY INVISIBLE (-2102 3225);
FORCEADD TAP..6
(-1950 3275);
FORCEPROP 3 LASTPIN (-1900 3275) SIG_NAME M_K_CLK_DP<3>
J 0
(-1890 3285);
DISPLAY 0.659574 (-1890 3285);
PAINT MONO (-1890 3285);
DISPLAY INVISIBLE (-1890 3285);
FORCEPROP 1 LASTPIN (-1900 3275) BN 3
J 0
(-1952 3283);
DISPLAY 0.617021 (-1952 3283);
PAINT PINK (-1952 3283);
FORCEPROP 2 LAST CDS_LIB mstr_standard
J 0
(-1950 3275);
PAINT MONO (-1950 3275);
DISPLAY INVISIBLE (-1950 3275);
FORCEPROP 1 LAST BODY_TYPE PLUMBING
J 0
(-1950 3225);
DISPLAY 1.234043 (-1950 3225);
PAINT GREEN (-1950 3225);
DISPLAY INVISIBLE (-1950 3225);
FORCEPROP 1 LAST HDL_TAP TRUE
J 0
(-1625 3150);
DISPLAY 1.234043 (-1625 3150);
PAINT GREEN (-1625 3150);
DISPLAY INVISIBLE (-1625 3150);
FORCEPROP 1 LAST PATH I38
J 0
(-1952 3275);
DISPLAY 0.872340 (-1952 3275);
PAINT GREEN (-1952 3275);
DISPLAY INVISIBLE (-1952 3275);
FORCEADD TAP..6
(-1600 2725);
FORCEPROP 3 LASTPIN (-1550 2725) SIG_NAME M_K_CKE<3>
J 0
(-1540 2735);
DISPLAY 0.659574 (-1540 2735);
PAINT MONO (-1540 2735);
DISPLAY INVISIBLE (-1540 2735);
FORCEPROP 1 LASTPIN (-1550 2725) BN 3
J 0
(-1600 2735);
DISPLAY 0.617021 (-1600 2735);
PAINT PINK (-1600 2735);
FORCEPROP 2 LAST CDS_LIB mstr_standard
J 0
(-1600 2725);
DISPLAY 0.787234 (-1600 2725);
PAINT MONO (-1600 2725);
DISPLAY INVISIBLE (-1600 2725);
FORCEPROP 1 LAST BODY_TYPE PLUMBING
J 0
(-1600 2675);
DISPLAY 1.234043 (-1600 2675);
PAINT GREEN (-1600 2675);
DISPLAY INVISIBLE (-1600 2675);
FORCEPROP 1 LAST HDL_TAP TRUE
J 0
(-1275 2600);
DISPLAY 1.234043 (-1275 2600);
PAINT GREEN (-1275 2600);
DISPLAY INVISIBLE (-1275 2600);
FORCEPROP 1 LAST PATH I39
J 0
(-1602 2725);
DISPLAY 0.872340 (-1602 2725);
PAINT GREEN (-1602 2725);
DISPLAY INVISIBLE (-1602 2725);
FORCEADD CAP_A..1
R 2
(-3000 1125);
FORCEPROP 1 LAST LOCATION C9M1
J 2
(-3050 1225);
DISPLAY 0.617021 (-3050 1225);
PAINT AQUA (-3050 1225);
FORCEPROP 1 LAST PART_NUMBER A36096-045
J 2
(-3050 975);
DISPLAY 0.617021 (-3050 975);
PAINT BLUE (-3050 975);
FORCEPROP 1 LAST VALUE 0.01UF
J 2
(-3050 1175);
DISPLAY 0.617021 (-3050 1175);
PAINT SKYBLUE (-3050 1175);
FORCEPROP 1 LAST TOLERANCE 10%
J 2
(-3050 1075);
DISPLAY 0.617021 (-3050 1075);
PAINT SKYBLUE (-3050 1075);
FORCEPROP 1 LAST PACK_TYPE 0402V
J 2
(-3050 925);
DISPLAY 0.617021 (-3050 925);
PAINT SKYBLUE (-3050 925);
FORCEPROP 1 LAST VOLTAGE 25V
J 2
(-3050 1125);
DISPLAY 0.617021 (-3050 1125);
PAINT SKYBLUE (-3050 1125);
FORCEPROP 1 LAST MATERIAL X7R
J 2
(-3050 1025);
DISPLAY 0.617021 (-3050 1025);
PAINT SKYBLUE (-3050 1025);
FORCEPROP 2 LAST CDS_LOCATION C9M1
J 2
(-3050 1225);
DISPLAY 0.617021 (-3050 1225);
PAINT AQUA (-3050 1225);
DISPLAY INVISIBLE (-3050 1225);
FORCEPROP 2 LAST BOM_COST MEM
J 0
(-3000 1125);
PAINT ORANGE (-3000 1125);
DISPLAY INVISIBLE (-3000 1125);
FORCEPROP 2 LAST CDS_LIB dev_discrete
J 0
(-3000 1125);
PAINT ORANGE (-3000 1125);
DISPLAY INVISIBLE (-3000 1125);
FORCEPROP 2 LAST CDS_SEC 1
J 0
(-3050 1325);
PAINT MONO (-3050 1325);
DISPLAY INVISIBLE (-3050 1325);
FORCEPROP 2 LAST $SEC 1
J 0
(-3050 1325);
PAINT MONO (-3050 1325);
DISPLAY INVISIBLE (-3050 1325);
FORCEPROP 1 LAST PATH I4
J 2
(-3050 1275);
DISPLAY 0.978723 (-3050 1275);
PAINT WHITE (-3050 1275);
DISPLAY INVISIBLE (-3050 1275);
FORCEPROP 2 LAST ROOM DDR4_CH_C
J 0
(-3000 1125);
PAINT ORANGE (-3000 1125);
DISPLAY INVISIBLE (-3000 1125);
FORCEPROP 1 LASTPIN (-3000 1225) $PN 1
J 2
(-3010 1205);
DISPLAY 0.787234 (-3010 1205);
PAINT ORANGE (-3010 1205);
DISPLAY INVISIBLE (-3010 1205);
FORCEPROP 1 LASTPIN (-3000 1025) $PN 2
J 2
(-3010 1005);
DISPLAY 0.787234 (-3010 1005);
PAINT ORANGE (-3010 1005);
DISPLAY INVISIBLE (-3010 1005);
FORCEADD TAP..6
(-1600 2925);
FORCEPROP 3 LASTPIN (-1550 2925) SIG_NAME M_K_CS_N<6>
J 0
(-1540 2935);
DISPLAY 0.659574 (-1540 2935);
PAINT MONO (-1540 2935);
DISPLAY INVISIBLE (-1540 2935);
FORCEPROP 1 LASTPIN (-1550 2925) BN 6
J 0
(-1600 2935);
DISPLAY 0.617021 (-1600 2935);
PAINT PINK (-1600 2935);
FORCEPROP 2 LAST CDS_LIB mstr_standard
J 0
(-1600 2925);
DISPLAY 0.787234 (-1600 2925);
PAINT MONO (-1600 2925);
DISPLAY INVISIBLE (-1600 2925);
FORCEPROP 1 LAST BODY_TYPE PLUMBING
J 0
(-1600 2875);
DISPLAY 1.234043 (-1600 2875);
PAINT GREEN (-1600 2875);
DISPLAY INVISIBLE (-1600 2875);
FORCEPROP 1 LAST HDL_TAP TRUE
J 0
(-1275 2800);
DISPLAY 1.234043 (-1275 2800);
PAINT GREEN (-1275 2800);
DISPLAY INVISIBLE (-1275 2800);
FORCEPROP 1 LAST PATH I40
J 0
(-1602 2925);
DISPLAY 0.872340 (-1602 2925);
PAINT GREEN (-1602 2925);
DISPLAY INVISIBLE (-1602 2925);
FORCEADD TAP..6
(-1600 2875);
FORCEPROP 3 LASTPIN (-1550 2875) SIG_NAME M_K_CS_N<5>
J 0
(-1540 2885);
DISPLAY 0.659574 (-1540 2885);
PAINT MONO (-1540 2885);
DISPLAY INVISIBLE (-1540 2885);
FORCEPROP 1 LASTPIN (-1550 2875) BN 5
J 0
(-1600 2885);
DISPLAY 0.617021 (-1600 2885);
PAINT PINK (-1600 2885);
FORCEPROP 2 LAST CDS_LIB mstr_standard
J 0
(-1600 2875);
DISPLAY 0.787234 (-1600 2875);
PAINT MONO (-1600 2875);
DISPLAY INVISIBLE (-1600 2875);
FORCEPROP 1 LAST BODY_TYPE PLUMBING
J 0
(-1600 2825);
DISPLAY 1.234043 (-1600 2825);
PAINT GREEN (-1600 2825);
DISPLAY INVISIBLE (-1600 2825);
FORCEPROP 1 LAST HDL_TAP TRUE
J 0
(-1275 2750);
DISPLAY 1.234043 (-1275 2750);
PAINT GREEN (-1275 2750);
DISPLAY INVISIBLE (-1275 2750);
FORCEPROP 1 LAST PATH I41
J 0
(-1602 2875);
DISPLAY 0.872340 (-1602 2875);
PAINT GREEN (-1602 2875);
DISPLAY INVISIBLE (-1602 2875);
FORCEADD TAP..6
(-1600 2825);
FORCEPROP 3 LASTPIN (-1550 2825) SIG_NAME M_K_CS_N<4>
J 0
(-1540 2835);
DISPLAY 0.659574 (-1540 2835);
PAINT MONO (-1540 2835);
DISPLAY INVISIBLE (-1540 2835);
FORCEPROP 1 LASTPIN (-1550 2825) BN 4
J 0
(-1600 2835);
DISPLAY 0.617021 (-1600 2835);
PAINT PINK (-1600 2835);
FORCEPROP 2 LAST CDS_LIB mstr_standard
J 0
(-1600 2825);
DISPLAY 0.787234 (-1600 2825);
PAINT MONO (-1600 2825);
DISPLAY INVISIBLE (-1600 2825);
FORCEPROP 1 LAST BODY_TYPE PLUMBING
J 0
(-1600 2775);
DISPLAY 1.234043 (-1600 2775);
PAINT GREEN (-1600 2775);
DISPLAY INVISIBLE (-1600 2775);
FORCEPROP 1 LAST HDL_TAP TRUE
J 0
(-1275 2700);
DISPLAY 1.234043 (-1275 2700);
PAINT GREEN (-1275 2700);
DISPLAY INVISIBLE (-1275 2700);
FORCEPROP 1 LAST PATH I42
J 0
(-1602 2825);
DISPLAY 0.872340 (-1602 2825);
PAINT GREEN (-1602 2825);
DISPLAY INVISIBLE (-1602 2825);
FORCEADD TAP..6
(-1600 2975);
FORCEPROP 3 LASTPIN (-1550 2975) SIG_NAME M_K_CS_N<7>
J 0
(-1540 2985);
DISPLAY 0.659574 (-1540 2985);
PAINT MONO (-1540 2985);
DISPLAY INVISIBLE (-1540 2985);
FORCEPROP 1 LASTPIN (-1550 2975) BN 7
J 0
(-1600 2985);
DISPLAY 0.617021 (-1600 2985);
PAINT PINK (-1600 2985);
FORCEPROP 2 LAST CDS_LIB mstr_standard
J 0
(-1600 2975);
DISPLAY 0.787234 (-1600 2975);
PAINT MONO (-1600 2975);
DISPLAY INVISIBLE (-1600 2975);
FORCEPROP 1 LAST BODY_TYPE PLUMBING
J 0
(-1600 2925);
DISPLAY 1.234043 (-1600 2925);
PAINT GREEN (-1600 2925);
DISPLAY INVISIBLE (-1600 2925);
FORCEPROP 1 LAST HDL_TAP TRUE
J 0
(-1275 2850);
DISPLAY 1.234043 (-1275 2850);
PAINT GREEN (-1275 2850);
DISPLAY INVISIBLE (-1275 2850);
FORCEPROP 1 LAST PATH I43
J 0
(-1602 2975);
DISPLAY 0.872340 (-1602 2975);
PAINT GREEN (-1602 2975);
DISPLAY INVISIBLE (-1602 2975);
FORCEADD TAP..6
(-1600 3425);
FORCEPROP 3 LASTPIN (-1550 3425) SIG_NAME M_K_BG<1>
J 0
(-1540 3435);
DISPLAY 0.659574 (-1540 3435);
PAINT MONO (-1540 3435);
DISPLAY INVISIBLE (-1540 3435);
FORCEPROP 1 LASTPIN (-1550 3425) BN 1
J 0
(-1600 3435);
DISPLAY 0.617021 (-1600 3435);
PAINT PINK (-1600 3435);
FORCEPROP 2 LAST CDS_LIB mstr_standard
J 0
(-1600 3425);
DISPLAY 0.787234 (-1600 3425);
PAINT MONO (-1600 3425);
DISPLAY INVISIBLE (-1600 3425);
FORCEPROP 1 LAST BODY_TYPE PLUMBING
J 0
(-1600 3375);
DISPLAY 1.234043 (-1600 3375);
PAINT GREEN (-1600 3375);
DISPLAY INVISIBLE (-1600 3375);
FORCEPROP 1 LAST HDL_TAP TRUE
J 0
(-1275 3300);
DISPLAY 1.234043 (-1275 3300);
PAINT GREEN (-1275 3300);
DISPLAY INVISIBLE (-1275 3300);
FORCEPROP 1 LAST PATH I44
J 0
(-1602 3425);
DISPLAY 0.872340 (-1602 3425);
PAINT GREEN (-1602 3425);
DISPLAY INVISIBLE (-1602 3425);
FORCEADD TAP..6
(-1600 3375);
FORCEPROP 3 LASTPIN (-1550 3375) SIG_NAME M_K_BG<0>
J 0
(-1540 3385);
DISPLAY 0.659574 (-1540 3385);
PAINT MONO (-1540 3385);
DISPLAY INVISIBLE (-1540 3385);
FORCEPROP 1 LASTPIN (-1550 3375) BN 0
J 0
(-1600 3385);
DISPLAY 0.617021 (-1600 3385);
PAINT PINK (-1600 3385);
FORCEPROP 2 LAST CDS_LIB mstr_standard
J 0
(-1600 3375);
DISPLAY 0.787234 (-1600 3375);
PAINT MONO (-1600 3375);
DISPLAY INVISIBLE (-1600 3375);
FORCEPROP 1 LAST BODY_TYPE PLUMBING
J 0
(-1600 3325);
DISPLAY 1.234043 (-1600 3325);
PAINT GREEN (-1600 3325);
DISPLAY INVISIBLE (-1600 3325);
FORCEPROP 1 LAST HDL_TAP TRUE
J 0
(-1275 3250);
DISPLAY 1.234043 (-1275 3250);
PAINT GREEN (-1275 3250);
DISPLAY INVISIBLE (-1275 3250);
FORCEPROP 1 LAST PATH I45
J 0
(-1602 3375);
DISPLAY 0.872340 (-1602 3375);
PAINT GREEN (-1602 3375);
DISPLAY INVISIBLE (-1602 3375);
FORCEADD TAP..6
(-1600 3675);
FORCEPROP 3 LASTPIN (-1550 3675) SIG_NAME M_K_MA<1>
J 0
(-1540 3685);
DISPLAY 0.659574 (-1540 3685);
PAINT MONO (-1540 3685);
DISPLAY INVISIBLE (-1540 3685);
FORCEPROP 1 LASTPIN (-1550 3675) BN 1
J 0
(-1600 3685);
DISPLAY 0.617021 (-1600 3685);
PAINT PINK (-1600 3685);
FORCEPROP 2 LAST CDS_LIB mstr_standard
J 2
(-1600 3675);
DISPLAY 0.787234 (-1600 3675);
PAINT MONO (-1600 3675);
DISPLAY INVISIBLE (-1600 3675);
FORCEPROP 1 LAST BODY_TYPE PLUMBING
J 0
(-1600 3625);
DISPLAY 1.234043 (-1600 3625);
PAINT GREEN (-1600 3625);
DISPLAY INVISIBLE (-1600 3625);
FORCEPROP 1 LAST HDL_TAP TRUE
J 0
(-1275 3550);
DISPLAY 1.234043 (-1275 3550);
PAINT GREEN (-1275 3550);
DISPLAY INVISIBLE (-1275 3550);
FORCEPROP 1 LAST PATH I46
J 0
(-1602 3675);
DISPLAY 0.872340 (-1602 3675);
PAINT GREEN (-1602 3675);
DISPLAY INVISIBLE (-1602 3675);
FORCEADD TAP..6
(-1600 3625);
FORCEPROP 3 LASTPIN (-1550 3625) SIG_NAME M_K_MA<0>
J 0
(-1540 3635);
DISPLAY 0.659574 (-1540 3635);
PAINT MONO (-1540 3635);
DISPLAY INVISIBLE (-1540 3635);
FORCEPROP 1 LASTPIN (-1550 3625) BN 0
J 0
(-1600 3635);
DISPLAY 0.617021 (-1600 3635);
PAINT PINK (-1600 3635);
FORCEPROP 2 LAST CDS_LIB mstr_standard
J 2
(-1600 3625);
DISPLAY 0.787234 (-1600 3625);
PAINT MONO (-1600 3625);
DISPLAY INVISIBLE (-1600 3625);
FORCEPROP 1 LAST BODY_TYPE PLUMBING
J 0
(-1600 3575);
DISPLAY 1.234043 (-1600 3575);
PAINT GREEN (-1600 3575);
DISPLAY INVISIBLE (-1600 3575);
FORCEPROP 1 LAST HDL_TAP TRUE
J 0
(-1275 3500);
DISPLAY 1.234043 (-1275 3500);
PAINT GREEN (-1275 3500);
DISPLAY INVISIBLE (-1275 3500);
FORCEPROP 1 LAST PATH I47
J 0
(-1602 3625);
DISPLAY 0.872340 (-1602 3625);
PAINT GREEN (-1602 3625);
DISPLAY INVISIBLE (-1602 3625);
FORCEADD TAP..6
(-1600 3475);
FORCEPROP 3 LASTPIN (-1550 3475) SIG_NAME M_K_BA<0>
J 0
(-1540 3485);
DISPLAY 0.659574 (-1540 3485);
PAINT MONO (-1540 3485);
DISPLAY INVISIBLE (-1540 3485);
FORCEPROP 1 LASTPIN (-1550 3475) BN 0
J 0
(-1600 3485);
DISPLAY 0.617021 (-1600 3485);
PAINT PINK (-1600 3485);
FORCEPROP 2 LAST CDS_LIB mstr_standard
J 0
(-1600 3475);
DISPLAY 0.787234 (-1600 3475);
PAINT MONO (-1600 3475);
DISPLAY INVISIBLE (-1600 3475);
FORCEPROP 1 LAST BODY_TYPE PLUMBING
J 0
(-1600 3425);
DISPLAY 1.234043 (-1600 3425);
PAINT GREEN (-1600 3425);
DISPLAY INVISIBLE (-1600 3425);
FORCEPROP 1 LAST HDL_TAP TRUE
J 0
(-1275 3350);
DISPLAY 1.234043 (-1275 3350);
PAINT GREEN (-1275 3350);
DISPLAY INVISIBLE (-1275 3350);
FORCEPROP 1 LAST PATH I48
J 0
(-1602 3475);
DISPLAY 0.872340 (-1602 3475);
PAINT GREEN (-1602 3475);
DISPLAY INVISIBLE (-1602 3475);
FORCEADD TAP..6
(-1600 3525);
FORCEPROP 3 LASTPIN (-1550 3525) SIG_NAME M_K_BA<1>
J 0
(-1540 3535);
DISPLAY 0.659574 (-1540 3535);
PAINT MONO (-1540 3535);
DISPLAY INVISIBLE (-1540 3535);
FORCEPROP 1 LASTPIN (-1550 3525) BN 1
J 0
(-1600 3535);
DISPLAY 0.617021 (-1600 3535);
PAINT PINK (-1600 3535);
FORCEPROP 2 LAST CDS_LIB mstr_standard
J 0
(-1600 3525);
DISPLAY 0.787234 (-1600 3525);
PAINT MONO (-1600 3525);
DISPLAY INVISIBLE (-1600 3525);
FORCEPROP 1 LAST BODY_TYPE PLUMBING
J 0
(-1600 3475);
DISPLAY 1.234043 (-1600 3475);
PAINT GREEN (-1600 3475);
DISPLAY INVISIBLE (-1600 3475);
FORCEPROP 1 LAST HDL_TAP TRUE
J 0
(-1275 3400);
DISPLAY 1.234043 (-1275 3400);
PAINT GREEN (-1275 3400);
DISPLAY INVISIBLE (-1275 3400);
FORCEPROP 1 LAST PATH I49
J 0
(-1602 3525);
DISPLAY 0.872340 (-1602 3525);
PAINT GREEN (-1602 3525);
DISPLAY INVISIBLE (-1602 3525);
FORCEADD PVPP_KLM..1
(-3500 1825);
FORCEPROP 3 LASTPIN (-3500 1775) SIG_NAME PVPP_KLM\g
J 0
(-3490 1785);
DISPLAY 0.659574 (-3490 1785);
PAINT MONO (-3490 1785);
DISPLAY INVISIBLE (-3490 1785);
FORCEPROP 1 LAST VOLTAGE 2.5V
J 0
(-3545 1782);
DISPLAY 0.340426 (-3545 1782);
PAINT SKYBLUE (-3545 1782);
DISPLAY INVISIBLE (-3545 1782);
FORCEPROP 0 LAST BOM_COST MEM
J 0
(-3500 1925);
PAINT ORANGE (-3500 1925);
DISPLAY INVISIBLE (-3500 1925);
FORCEPROP 2 LAST CDS_LIB mstr_symbols
J 0
(-3500 1825);
PAINT ORANGE (-3500 1825);
DISPLAY INVISIBLE (-3500 1825);
FORCEPROP 1 LAST BODY_TYPE PLUMBING
J 0
(-3545 1782);
DISPLAY 0.340426 (-3545 1782);
PAINT GREEN (-3545 1782);
DISPLAY INVISIBLE (-3545 1782);
FORCEPROP 1 LAST PATH I5
J 0
(-3450 1850);
DISPLAY 0.872340 (-3450 1850);
PAINT AQUA (-3450 1850);
DISPLAY INVISIBLE (-3450 1850);
FORCEPROP 2 LAST ROOM DDR4_CH_C
J 0
(-3500 1925);
PAINT ORANGE (-3500 1925);
DISPLAY INVISIBLE (-3500 1925);
FORCEPROP 1 LAST HDL_POWER PVPP_KLM
J 1
(-3500 1875);
DISPLAY 0.872340 (-3500 1875);
PAINT GREEN (-3500 1875);
DISPLAY INVISIBLE (-3500 1875);
FORCEADD TAP..6
R 2
(-100 1325);
FORCEPROP 3 LASTPIN (-150 1325) SIG_NAME M_K_DQ<0>
J 0
(-140 1335);
DISPLAY 0.659574 (-140 1335);
PAINT MONO (-140 1335);
DISPLAY INVISIBLE (-140 1335);
FORCEPROP 1 LASTPIN (-150 1325) BN 0
J 2
(-100 1335);
DISPLAY 0.617021 (-100 1335);
PAINT PINK (-100 1335);
FORCEPROP 2 LAST CDS_LIB mstr_standard
J 2
(-100 1325);
DISPLAY 0.787234 (-100 1325);
PAINT MONO (-100 1325);
DISPLAY INVISIBLE (-100 1325);
FORCEPROP 1 LAST BODY_TYPE PLUMBING
J 2
(-100 1275);
DISPLAY 1.234043 (-100 1275);
PAINT GREEN (-100 1275);
DISPLAY INVISIBLE (-100 1275);
FORCEPROP 1 LAST HDL_TAP TRUE
J 2
(-425 1200);
DISPLAY 1.234043 (-425 1200);
PAINT GREEN (-425 1200);
DISPLAY INVISIBLE (-425 1200);
FORCEPROP 1 LAST PATH I50
J 2
(-98 1325);
DISPLAY 0.872340 (-98 1325);
PAINT GREEN (-98 1325);
DISPLAY INVISIBLE (-98 1325);
FORCEADD TAP..6
R 2
(-100 1375);
FORCEPROP 3 LASTPIN (-150 1375) SIG_NAME M_K_DQ<1>
J 0
(-140 1385);
DISPLAY 0.659574 (-140 1385);
PAINT MONO (-140 1385);
DISPLAY INVISIBLE (-140 1385);
FORCEPROP 1 LASTPIN (-150 1375) BN 1
J 2
(-100 1385);
DISPLAY 0.617021 (-100 1385);
PAINT PINK (-100 1385);
FORCEPROP 2 LAST CDS_LIB mstr_standard
J 2
(-100 1375);
DISPLAY 0.787234 (-100 1375);
PAINT MONO (-100 1375);
DISPLAY INVISIBLE (-100 1375);
FORCEPROP 1 LAST BODY_TYPE PLUMBING
J 2
(-100 1325);
DISPLAY 1.234043 (-100 1325);
PAINT GREEN (-100 1325);
DISPLAY INVISIBLE (-100 1325);
FORCEPROP 1 LAST HDL_TAP TRUE
J 2
(-425 1250);
DISPLAY 1.234043 (-425 1250);
PAINT GREEN (-425 1250);
DISPLAY INVISIBLE (-425 1250);
FORCEPROP 1 LAST PATH I51
J 2
(-98 1375);
DISPLAY 0.872340 (-98 1375);
PAINT GREEN (-98 1375);
DISPLAY INVISIBLE (-98 1375);
FORCEADD TAP..6
R 2
(-100 1425);
FORCEPROP 3 LASTPIN (-150 1425) SIG_NAME M_K_DQ<2>
J 0
(-140 1435);
DISPLAY 0.659574 (-140 1435);
PAINT MONO (-140 1435);
DISPLAY INVISIBLE (-140 1435);
FORCEPROP 1 LASTPIN (-150 1425) BN 2
J 2
(-100 1435);
DISPLAY 0.617021 (-100 1435);
PAINT PINK (-100 1435);
FORCEPROP 2 LAST CDS_LIB mstr_standard
J 2
(-100 1425);
DISPLAY 0.787234 (-100 1425);
PAINT MONO (-100 1425);
DISPLAY INVISIBLE (-100 1425);
FORCEPROP 1 LAST BODY_TYPE PLUMBING
J 2
(-100 1375);
DISPLAY 1.234043 (-100 1375);
PAINT GREEN (-100 1375);
DISPLAY INVISIBLE (-100 1375);
FORCEPROP 1 LAST HDL_TAP TRUE
J 2
(-425 1300);
DISPLAY 1.234043 (-425 1300);
PAINT GREEN (-425 1300);
DISPLAY INVISIBLE (-425 1300);
FORCEPROP 1 LAST PATH I52
J 2
(-98 1425);
DISPLAY 0.872340 (-98 1425);
PAINT GREEN (-98 1425);
DISPLAY INVISIBLE (-98 1425);
FORCEADD TAP..6
R 2
(-100 1475);
FORCEPROP 3 LASTPIN (-150 1475) SIG_NAME M_K_DQ<3>
J 0
(-140 1485);
DISPLAY 0.659574 (-140 1485);
PAINT MONO (-140 1485);
DISPLAY INVISIBLE (-140 1485);
FORCEPROP 1 LASTPIN (-150 1475) BN 3
J 2
(-100 1485);
DISPLAY 0.617021 (-100 1485);
PAINT PINK (-100 1485);
FORCEPROP 2 LAST CDS_LIB mstr_standard
J 2
(-100 1475);
DISPLAY 0.787234 (-100 1475);
PAINT MONO (-100 1475);
DISPLAY INVISIBLE (-100 1475);
FORCEPROP 1 LAST BODY_TYPE PLUMBING
J 2
(-100 1425);
DISPLAY 1.234043 (-100 1425);
PAINT GREEN (-100 1425);
DISPLAY INVISIBLE (-100 1425);
FORCEPROP 1 LAST HDL_TAP TRUE
J 2
(-425 1350);
DISPLAY 1.234043 (-425 1350);
PAINT GREEN (-425 1350);
DISPLAY INVISIBLE (-425 1350);
FORCEPROP 1 LAST PATH I53
J 2
(-98 1475);
DISPLAY 0.872340 (-98 1475);
PAINT GREEN (-98 1475);
DISPLAY INVISIBLE (-98 1475);
FORCEADD TAP..6
R 2
(-100 1525);
FORCEPROP 3 LASTPIN (-150 1525) SIG_NAME M_K_DQ<4>
J 0
(-140 1535);
DISPLAY 0.659574 (-140 1535);
PAINT MONO (-140 1535);
DISPLAY INVISIBLE (-140 1535);
FORCEPROP 1 LASTPIN (-150 1525) BN 4
J 2
(-100 1535);
DISPLAY 0.617021 (-100 1535);
PAINT PINK (-100 1535);
FORCEPROP 2 LAST CDS_LIB mstr_standard
J 2
(-100 1525);
DISPLAY 0.787234 (-100 1525);
PAINT MONO (-100 1525);
DISPLAY INVISIBLE (-100 1525);
FORCEPROP 1 LAST BODY_TYPE PLUMBING
J 2
(-100 1475);
DISPLAY 1.234043 (-100 1475);
PAINT GREEN (-100 1475);
DISPLAY INVISIBLE (-100 1475);
FORCEPROP 1 LAST HDL_TAP TRUE
J 2
(-425 1400);
DISPLAY 1.234043 (-425 1400);
PAINT GREEN (-425 1400);
DISPLAY INVISIBLE (-425 1400);
FORCEPROP 1 LAST PATH I54
J 2
(-98 1525);
DISPLAY 0.872340 (-98 1525);
PAINT GREEN (-98 1525);
DISPLAY INVISIBLE (-98 1525);
FORCEADD TAP..6
R 2
(-100 1625);
FORCEPROP 3 LASTPIN (-150 1625) SIG_NAME M_K_DQ<6>
J 0
(-140 1635);
DISPLAY 0.659574 (-140 1635);
PAINT MONO (-140 1635);
DISPLAY INVISIBLE (-140 1635);
FORCEPROP 1 LASTPIN (-150 1625) BN 6
J 2
(-100 1635);
DISPLAY 0.617021 (-100 1635);
PAINT PINK (-100 1635);
FORCEPROP 2 LAST CDS_LIB mstr_standard
J 2
(-100 1625);
DISPLAY 0.787234 (-100 1625);
PAINT MONO (-100 1625);
DISPLAY INVISIBLE (-100 1625);
FORCEPROP 1 LAST BODY_TYPE PLUMBING
J 2
(-100 1575);
DISPLAY 1.234043 (-100 1575);
PAINT GREEN (-100 1575);
DISPLAY INVISIBLE (-100 1575);
FORCEPROP 1 LAST HDL_TAP TRUE
J 2
(-425 1500);
DISPLAY 1.234043 (-425 1500);
PAINT GREEN (-425 1500);
DISPLAY INVISIBLE (-425 1500);
FORCEPROP 1 LAST PATH I55
J 2
(-98 1625);
DISPLAY 0.872340 (-98 1625);
PAINT GREEN (-98 1625);
DISPLAY INVISIBLE (-98 1625);
FORCEADD TAP..6
R 2
(-100 1575);
FORCEPROP 3 LASTPIN (-150 1575) SIG_NAME M_K_DQ<5>
J 0
(-140 1585);
DISPLAY 0.659574 (-140 1585);
PAINT MONO (-140 1585);
DISPLAY INVISIBLE (-140 1585);
FORCEPROP 1 LASTPIN (-150 1575) BN 5
J 2
(-100 1585);
DISPLAY 0.617021 (-100 1585);
PAINT PINK (-100 1585);
FORCEPROP 2 LAST CDS_LIB mstr_standard
J 2
(-100 1575);
DISPLAY 0.787234 (-100 1575);
PAINT MONO (-100 1575);
DISPLAY INVISIBLE (-100 1575);
FORCEPROP 1 LAST BODY_TYPE PLUMBING
J 2
(-100 1525);
DISPLAY 1.234043 (-100 1525);
PAINT GREEN (-100 1525);
DISPLAY INVISIBLE (-100 1525);
FORCEPROP 1 LAST HDL_TAP TRUE
J 2
(-425 1450);
DISPLAY 1.234043 (-425 1450);
PAINT GREEN (-425 1450);
DISPLAY INVISIBLE (-425 1450);
FORCEPROP 1 LAST PATH I56
J 2
(-98 1575);
DISPLAY 0.872340 (-98 1575);
PAINT GREEN (-98 1575);
DISPLAY INVISIBLE (-98 1575);
FORCEADD SCONN288_H44441003..4
(1450 1725);
FORCEPROP 1 LAST LOCATION J9M1
J 0
(1000 2825);
DISPLAY 0.617021 (1000 2825);
PAINT AQUA (1000 2825);
FORCEPROP 1 LAST PART_NUMBER H44441-003
J 0
(1000 675);
DISPLAY 0.617021 (1000 675);
PAINT BLUE (1000 675);
FORCEPROP 1 LAST MATERIAL SCONN
J 0
(1000 2775);
DISPLAY 0.617021 (1000 2775);
PAINT SKYBLUE (1000 2775);
FORCEPROP 2 LASTPIN (950 2275) $PN 77
J 2
(940 2285);
DISPLAY 0.617021 (940 2285);
PAINT ORANGE (940 2285);
FORCEPROP 2 LASTPIN (950 2225) $PN 221
J 2
(940 2235);
DISPLAY 0.617021 (940 2235);
PAINT ORANGE (940 2235);
FORCEPROP 2 LASTPIN (950 2575) $PN 142
J 2
(940 2585);
DISPLAY 0.617021 (940 2585);
PAINT ORANGE (940 2585);
FORCEPROP 2 LASTPIN (950 2525) $PN 143
J 2
(940 2535);
DISPLAY 0.617021 (940 2535);
PAINT ORANGE (940 2535);
FORCEPROP 2 LASTPIN (950 2475) $PN 288
J 2
(940 2485);
DISPLAY 0.617021 (940 2485);
PAINT ORANGE (940 2485);
FORCEPROP 2 LASTPIN (950 2425) $PN 286
J 2
(940 2435);
DISPLAY 0.617021 (940 2435);
PAINT ORANGE (940 2435);
FORCEPROP 2 LASTPIN (950 2375) $PN 287
J 2
(940 2385);
DISPLAY 0.617021 (940 2385);
PAINT ORANGE (940 2385);
FORCEPROP 2 LASTPIN (950 2125) $PN 59
J 2
(940 2135);
DISPLAY 0.617021 (940 2135);
PAINT ORANGE (940 2135);
FORCEPROP 2 LASTPIN (950 2075) $PN 61
J 2
(940 2085);
DISPLAY 0.617021 (940 2085);
PAINT ORANGE (940 2085);
FORCEPROP 2 LASTPIN (950 2025) $PN 64
J 2
(940 2035);
DISPLAY 0.617021 (940 2035);
PAINT ORANGE (940 2035);
FORCEPROP 2 LASTPIN (950 1975) $PN 67
J 2
(940 1985);
DISPLAY 0.617021 (940 1985);
PAINT ORANGE (940 1985);
FORCEPROP 2 LASTPIN (950 1925) $PN 70
J 2
(940 1935);
DISPLAY 0.617021 (940 1935);
PAINT ORANGE (940 1935);
FORCEPROP 2 LASTPIN (950 1875) $PN 73
J 2
(940 1885);
DISPLAY 0.617021 (940 1885);
PAINT ORANGE (940 1885);
FORCEPROP 2 LASTPIN (950 1825) $PN 76
J 2
(940 1835);
DISPLAY 0.617021 (940 1835);
PAINT ORANGE (940 1835);
FORCEPROP 2 LASTPIN (950 1775) $PN 80
J 2
(940 1785);
DISPLAY 0.617021 (940 1785);
PAINT ORANGE (940 1785);
FORCEPROP 2 LASTPIN (950 1725) $PN 83
J 2
(940 1735);
DISPLAY 0.617021 (940 1735);
PAINT ORANGE (940 1735);
FORCEPROP 2 LASTPIN (950 1675) $PN 85
J 2
(940 1685);
DISPLAY 0.617021 (940 1685);
PAINT ORANGE (940 1685);
FORCEPROP 2 LASTPIN (950 1625) $PN 88
J 2
(940 1635);
DISPLAY 0.617021 (940 1635);
PAINT ORANGE (940 1635);
FORCEPROP 2 LASTPIN (950 1575) $PN 90
J 2
(940 1585);
DISPLAY 0.617021 (940 1585);
PAINT ORANGE (940 1585);
FORCEPROP 2 LASTPIN (950 1525) $PN 92
J 2
(940 1535);
DISPLAY 0.617021 (940 1535);
PAINT ORANGE (940 1535);
FORCEPROP 2 LASTPIN (950 1475) $PN 204
J 2
(940 1485);
DISPLAY 0.617021 (940 1485);
PAINT ORANGE (940 1485);
FORCEPROP 2 LASTPIN (950 1425) $PN 206
J 2
(940 1435);
DISPLAY 0.617021 (940 1435);
PAINT ORANGE (940 1435);
FORCEPROP 2 LASTPIN (950 1375) $PN 209
J 2
(940 1385);
DISPLAY 0.617021 (940 1385);
PAINT ORANGE (940 1385);
FORCEPROP 2 LASTPIN (950 1325) $PN 212
J 2
(940 1335);
DISPLAY 0.617021 (940 1335);
PAINT ORANGE (940 1335);
FORCEPROP 2 LASTPIN (950 1275) $PN 215
J 2
(940 1285);
DISPLAY 0.617021 (940 1285);
PAINT ORANGE (940 1285);
FORCEPROP 2 LASTPIN (950 1225) $PN 217
J 2
(940 1235);
DISPLAY 0.617021 (940 1235);
PAINT ORANGE (940 1235);
FORCEPROP 2 LASTPIN (950 1175) $PN 220
J 2
(940 1185);
DISPLAY 0.617021 (940 1185);
PAINT ORANGE (940 1185);
FORCEPROP 2 LASTPIN (950 1125) $PN 223
J 2
(940 1135);
DISPLAY 0.617021 (940 1135);
PAINT ORANGE (940 1135);
FORCEPROP 2 LASTPIN (950 1075) $PN 226
J 2
(940 1085);
DISPLAY 0.617021 (940 1085);
PAINT ORANGE (940 1085);
FORCEPROP 2 LASTPIN (950 1025) $PN 229
J 2
(940 1035);
DISPLAY 0.617021 (940 1035);
PAINT ORANGE (940 1035);
FORCEPROP 2 LASTPIN (950 975) $PN 231
J 2
(940 985);
DISPLAY 0.617021 (940 985);
PAINT ORANGE (940 985);
FORCEPROP 2 LASTPIN (950 925) $PN 233
J 2
(940 935);
DISPLAY 0.617021 (940 935);
PAINT ORANGE (940 935);
FORCEPROP 2 LASTPIN (950 875) $PN 236
J 2
(940 885);
DISPLAY 0.617021 (940 885);
PAINT ORANGE (940 885);
FORCEPROP 2 LASTPIN (1950 2575) $PN 1
J 0
(1960 2585);
DISPLAY 0.617021 (1960 2585);
PAINT ORANGE (1960 2585);
FORCEPROP 2 LASTPIN (1950 2525) $PN 145
J 0
(1960 2535);
DISPLAY 0.617021 (1960 2535);
PAINT ORANGE (1960 2535);
FORCEPROP 1 LAST PACK_TYPE PIP
J 0
(1000 2875);
PAINT SKYBLUE (1000 2875);
DISPLAY INVISIBLE (1000 2875);
FORCEPROP 2 LAST BOM_COST MEM
J 0
(1450 1725);
PAINT ORANGE (1450 1725);
DISPLAY INVISIBLE (1450 1725);
FORCEPROP 2 LAST CDS_LIB mstr_sconn
J 0
(1450 1725);
PAINT ORANGE (1450 1725);
DISPLAY INVISIBLE (1450 1725);
FORCEPROP 2 LAST SEC_TYPE PIP
J 0
(1000 2875);
DISPLAY 1.021277 (1000 2875);
PAINT ORANGE (1000 2875);
DISPLAY INVISIBLE (1000 2875);
FORCEPROP 2 LAST SEC 4
J 0
(1000 2875);
DISPLAY 0.680851 (1000 2875);
PAINT MONO (1000 2875);
DISPLAY INVISIBLE (1000 2875);
FORCEPROP 2 LAST CDS_LOCATION J9M1
J 0
(1000 2825);
DISPLAY 0.617021 (1000 2825);
PAINT AQUA (1000 2825);
DISPLAY INVISIBLE (1000 2825);
FORCEPROP 1 LAST PATH I57
J 0
(1450 2775);
PAINT GREEN (1450 2775);
DISPLAY INVISIBLE (1450 2775);
FORCEPROP 2 LAST ROOM DDR4_CH_K
J 0
(1450 1725);
PAINT ORANGE (1450 1725);
DISPLAY INVISIBLE (1450 1725);
FORCEADD TAP..6
R 2
(-100 1775);
FORCEPROP 3 LASTPIN (-150 1775) SIG_NAME M_K_DQ<9>
J 0
(-140 1785);
DISPLAY 0.659574 (-140 1785);
PAINT MONO (-140 1785);
DISPLAY INVISIBLE (-140 1785);
FORCEPROP 1 LASTPIN (-150 1775) BN 9
J 2
(-100 1785);
DISPLAY 0.617021 (-100 1785);
PAINT PINK (-100 1785);
FORCEPROP 2 LAST CDS_LIB mstr_standard
J 2
(-100 1775);
DISPLAY 0.787234 (-100 1775);
PAINT MONO (-100 1775);
DISPLAY INVISIBLE (-100 1775);
FORCEPROP 1 LAST BODY_TYPE PLUMBING
J 2
(-100 1725);
DISPLAY 1.234043 (-100 1725);
PAINT GREEN (-100 1725);
DISPLAY INVISIBLE (-100 1725);
FORCEPROP 1 LAST HDL_TAP TRUE
J 2
(-425 1650);
DISPLAY 1.234043 (-425 1650);
PAINT GREEN (-425 1650);
DISPLAY INVISIBLE (-425 1650);
FORCEPROP 1 LAST PATH I58
J 2
(-98 1775);
DISPLAY 0.872340 (-98 1775);
PAINT GREEN (-98 1775);
DISPLAY INVISIBLE (-98 1775);
FORCEADD TAP..6
R 2
(-100 1675);
FORCEPROP 3 LASTPIN (-150 1675) SIG_NAME M_K_DQ<7>
J 0
(-140 1685);
DISPLAY 0.659574 (-140 1685);
PAINT MONO (-140 1685);
DISPLAY INVISIBLE (-140 1685);
FORCEPROP 1 LASTPIN (-150 1675) BN 7
J 2
(-100 1685);
DISPLAY 0.617021 (-100 1685);
PAINT PINK (-100 1685);
FORCEPROP 2 LAST CDS_LIB mstr_standard
J 2
(-100 1675);
DISPLAY 0.787234 (-100 1675);
PAINT MONO (-100 1675);
DISPLAY INVISIBLE (-100 1675);
FORCEPROP 1 LAST BODY_TYPE PLUMBING
J 2
(-100 1625);
DISPLAY 1.234043 (-100 1625);
PAINT GREEN (-100 1625);
DISPLAY INVISIBLE (-100 1625);
FORCEPROP 1 LAST HDL_TAP TRUE
J 2
(-425 1550);
DISPLAY 1.234043 (-425 1550);
PAINT GREEN (-425 1550);
DISPLAY INVISIBLE (-425 1550);
FORCEPROP 1 LAST PATH I59
J 2
(-98 1675);
DISPLAY 0.872340 (-98 1675);
PAINT GREEN (-98 1675);
DISPLAY INVISIBLE (-98 1675);
FORCEADD OFFPAGE..5
(-2425 1825);
FORCEPROP 2 LAST $XR0 83 
J 0
(-2649 1825);
DISPLAY 0.638298 (-2649 1825);
PAINT MONO (-2649 1825);
FORCEPROP 2 LAST $XR1 60 
J 0
(-2739 1825);
DISPLAY 0.638298 (-2739 1825);
PAINT MONO (-2739 1825);
FORCEPROP 2 LAST CDS_LIB mstr_standard
J 0
(-2425 1825);
DISPLAY 0.787234 (-2425 1825);
PAINT MONO (-2425 1825);
DISPLAY INVISIBLE (-2425 1825);
FORCEPROP 1 LAST OFFPAGE TRUE
J 0
(-2100 1700);
DISPLAY 1.404255 (-2100 1700);
PAINT GREEN (-2100 1700);
DISPLAY INVISIBLE (-2100 1700);
FORCEPROP 1 LAST COMMENT_BODY TRUE
J 0
(-2325 1750);
DISPLAY 1.404255 (-2325 1750);
PAINT GREEN (-2325 1750);
DISPLAY INVISIBLE (-2325 1750);
FORCEPROP 2 LAST PATH I6
J 0
(-2625 1875);
DISPLAY 1.021277 (-2625 1875);
PAINT ORANGE (-2625 1875);
DISPLAY INVISIBLE (-2625 1875);
FORCEADD TAP..6
R 2
(-100 1725);
FORCEPROP 3 LASTPIN (-150 1725) SIG_NAME M_K_DQ<8>
J 0
(-140 1735);
DISPLAY 0.659574 (-140 1735);
PAINT MONO (-140 1735);
DISPLAY INVISIBLE (-140 1735);
FORCEPROP 1 LASTPIN (-150 1725) BN 8
J 2
(-100 1735);
DISPLAY 0.617021 (-100 1735);
PAINT PINK (-100 1735);
FORCEPROP 2 LAST CDS_LIB mstr_standard
J 2
(-100 1725);
DISPLAY 0.787234 (-100 1725);
PAINT MONO (-100 1725);
DISPLAY INVISIBLE (-100 1725);
FORCEPROP 1 LAST BODY_TYPE PLUMBING
J 2
(-100 1675);
DISPLAY 1.234043 (-100 1675);
PAINT GREEN (-100 1675);
DISPLAY INVISIBLE (-100 1675);
FORCEPROP 1 LAST HDL_TAP TRUE
J 2
(-425 1600);
DISPLAY 1.234043 (-425 1600);
PAINT GREEN (-425 1600);
DISPLAY INVISIBLE (-425 1600);
FORCEPROP 1 LAST PATH I60
J 2
(-98 1725);
DISPLAY 0.872340 (-98 1725);
PAINT GREEN (-98 1725);
DISPLAY INVISIBLE (-98 1725);
FORCEADD TAP..6
R 2
(-100 1875);
FORCEPROP 3 LASTPIN (-150 1875) SIG_NAME M_K_DQ<11>
J 0
(-140 1885);
DISPLAY 0.659574 (-140 1885);
PAINT MONO (-140 1885);
DISPLAY INVISIBLE (-140 1885);
FORCEPROP 1 LASTPIN (-150 1875) BN 11
J 2
(-100 1885);
DISPLAY 0.617021 (-100 1885);
PAINT PINK (-100 1885);
FORCEPROP 2 LAST CDS_LIB mstr_standard
J 2
(-100 1875);
DISPLAY 0.787234 (-100 1875);
PAINT MONO (-100 1875);
DISPLAY INVISIBLE (-100 1875);
FORCEPROP 1 LAST BODY_TYPE PLUMBING
J 2
(-100 1825);
DISPLAY 1.234043 (-100 1825);
PAINT GREEN (-100 1825);
DISPLAY INVISIBLE (-100 1825);
FORCEPROP 1 LAST HDL_TAP TRUE
J 2
(-425 1750);
DISPLAY 1.234043 (-425 1750);
PAINT GREEN (-425 1750);
DISPLAY INVISIBLE (-425 1750);
FORCEPROP 1 LAST PATH I61
J 2
(-98 1875);
DISPLAY 0.872340 (-98 1875);
PAINT GREEN (-98 1875);
DISPLAY INVISIBLE (-98 1875);
FORCEADD TAP..6
R 2
(-100 1925);
FORCEPROP 3 LASTPIN (-150 1925) SIG_NAME M_K_DQ<12>
J 0
(-140 1935);
DISPLAY 0.659574 (-140 1935);
PAINT MONO (-140 1935);
DISPLAY INVISIBLE (-140 1935);
FORCEPROP 1 LASTPIN (-150 1925) BN 12
J 2
(-100 1935);
DISPLAY 0.617021 (-100 1935);
PAINT PINK (-100 1935);
FORCEPROP 2 LAST CDS_LIB mstr_standard
J 2
(-100 1925);
DISPLAY 0.787234 (-100 1925);
PAINT MONO (-100 1925);
DISPLAY INVISIBLE (-100 1925);
FORCEPROP 1 LAST BODY_TYPE PLUMBING
J 2
(-100 1875);
DISPLAY 1.234043 (-100 1875);
PAINT GREEN (-100 1875);
DISPLAY INVISIBLE (-100 1875);
FORCEPROP 1 LAST HDL_TAP TRUE
J 2
(-425 1800);
DISPLAY 1.234043 (-425 1800);
PAINT GREEN (-425 1800);
DISPLAY INVISIBLE (-425 1800);
FORCEPROP 1 LAST PATH I62
J 2
(-98 1925);
DISPLAY 0.872340 (-98 1925);
PAINT GREEN (-98 1925);
DISPLAY INVISIBLE (-98 1925);
FORCEADD TAP..6
R 2
(-100 1825);
FORCEPROP 3 LASTPIN (-150 1825) SIG_NAME M_K_DQ<10>
J 0
(-140 1835);
DISPLAY 0.659574 (-140 1835);
PAINT MONO (-140 1835);
DISPLAY INVISIBLE (-140 1835);
FORCEPROP 1 LASTPIN (-150 1825) BN 10
J 2
(-100 1835);
DISPLAY 0.617021 (-100 1835);
PAINT PINK (-100 1835);
FORCEPROP 2 LAST CDS_LIB mstr_standard
J 2
(-100 1825);
DISPLAY 0.787234 (-100 1825);
PAINT MONO (-100 1825);
DISPLAY INVISIBLE (-100 1825);
FORCEPROP 1 LAST BODY_TYPE PLUMBING
J 2
(-100 1775);
DISPLAY 1.234043 (-100 1775);
PAINT GREEN (-100 1775);
DISPLAY INVISIBLE (-100 1775);
FORCEPROP 1 LAST HDL_TAP TRUE
J 2
(-425 1700);
DISPLAY 1.234043 (-425 1700);
PAINT GREEN (-425 1700);
DISPLAY INVISIBLE (-425 1700);
FORCEPROP 1 LAST PATH I63
J 2
(-98 1825);
DISPLAY 0.872340 (-98 1825);
PAINT GREEN (-98 1825);
DISPLAY INVISIBLE (-98 1825);
FORCEADD TAP..6
R 2
(-100 2025);
FORCEPROP 3 LASTPIN (-150 2025) SIG_NAME M_K_DQ<14>
J 0
(-140 2035);
DISPLAY 0.659574 (-140 2035);
PAINT MONO (-140 2035);
DISPLAY INVISIBLE (-140 2035);
FORCEPROP 1 LASTPIN (-150 2025) BN 14
J 2
(-100 2035);
DISPLAY 0.617021 (-100 2035);
PAINT PINK (-100 2035);
FORCEPROP 2 LAST CDS_LIB mstr_standard
J 2
(-100 2025);
DISPLAY 0.787234 (-100 2025);
PAINT MONO (-100 2025);
DISPLAY INVISIBLE (-100 2025);
FORCEPROP 1 LAST BODY_TYPE PLUMBING
J 2
(-100 1975);
DISPLAY 1.234043 (-100 1975);
PAINT GREEN (-100 1975);
DISPLAY INVISIBLE (-100 1975);
FORCEPROP 1 LAST HDL_TAP TRUE
J 2
(-425 1900);
DISPLAY 1.234043 (-425 1900);
PAINT GREEN (-425 1900);
DISPLAY INVISIBLE (-425 1900);
FORCEPROP 1 LAST PATH I64
J 2
(-98 2025);
DISPLAY 0.872340 (-98 2025);
PAINT GREEN (-98 2025);
DISPLAY INVISIBLE (-98 2025);
FORCEADD TAP..6
R 2
(-100 1975);
FORCEPROP 3 LASTPIN (-150 1975) SIG_NAME M_K_DQ<13>
J 0
(-140 1985);
DISPLAY 0.659574 (-140 1985);
PAINT MONO (-140 1985);
DISPLAY INVISIBLE (-140 1985);
FORCEPROP 1 LASTPIN (-150 1975) BN 13
J 2
(-100 1985);
DISPLAY 0.617021 (-100 1985);
PAINT PINK (-100 1985);
FORCEPROP 2 LAST CDS_LIB mstr_standard
J 2
(-100 1975);
DISPLAY 0.787234 (-100 1975);
PAINT MONO (-100 1975);
DISPLAY INVISIBLE (-100 1975);
FORCEPROP 1 LAST BODY_TYPE PLUMBING
J 2
(-100 1925);
DISPLAY 1.234043 (-100 1925);
PAINT GREEN (-100 1925);
DISPLAY INVISIBLE (-100 1925);
FORCEPROP 1 LAST HDL_TAP TRUE
J 2
(-425 1850);
DISPLAY 1.234043 (-425 1850);
PAINT GREEN (-425 1850);
DISPLAY INVISIBLE (-425 1850);
FORCEPROP 1 LAST PATH I65
J 2
(-98 1975);
DISPLAY 0.872340 (-98 1975);
PAINT GREEN (-98 1975);
DISPLAY INVISIBLE (-98 1975);
FORCEADD TAP..6
R 2
(-100 2125);
FORCEPROP 3 LASTPIN (-150 2125) SIG_NAME M_K_DQ<16>
J 0
(-140 2135);
DISPLAY 0.659574 (-140 2135);
PAINT MONO (-140 2135);
DISPLAY INVISIBLE (-140 2135);
FORCEPROP 1 LASTPIN (-150 2125) BN 16
J 2
(-100 2135);
DISPLAY 0.617021 (-100 2135);
PAINT PINK (-100 2135);
FORCEPROP 2 LAST CDS_LIB mstr_standard
J 2
(-100 2125);
DISPLAY 0.787234 (-100 2125);
PAINT MONO (-100 2125);
DISPLAY INVISIBLE (-100 2125);
FORCEPROP 1 LAST BODY_TYPE PLUMBING
J 2
(-100 2075);
DISPLAY 1.234043 (-100 2075);
PAINT GREEN (-100 2075);
DISPLAY INVISIBLE (-100 2075);
FORCEPROP 1 LAST HDL_TAP TRUE
J 2
(-425 2000);
DISPLAY 1.234043 (-425 2000);
PAINT GREEN (-425 2000);
DISPLAY INVISIBLE (-425 2000);
FORCEPROP 1 LAST PATH I66
J 2
(-98 2125);
DISPLAY 0.872340 (-98 2125);
PAINT GREEN (-98 2125);
DISPLAY INVISIBLE (-98 2125);
FORCEADD TAP..6
R 2
(-100 2175);
FORCEPROP 3 LASTPIN (-150 2175) SIG_NAME M_K_DQ<17>
J 0
(-140 2185);
DISPLAY 0.659574 (-140 2185);
PAINT MONO (-140 2185);
DISPLAY INVISIBLE (-140 2185);
FORCEPROP 1 LASTPIN (-150 2175) BN 17
J 2
(-100 2185);
DISPLAY 0.617021 (-100 2185);
PAINT PINK (-100 2185);
FORCEPROP 2 LAST CDS_LIB mstr_standard
J 2
(-100 2175);
DISPLAY 0.787234 (-100 2175);
PAINT MONO (-100 2175);
DISPLAY INVISIBLE (-100 2175);
FORCEPROP 1 LAST BODY_TYPE PLUMBING
J 2
(-100 2125);
DISPLAY 1.234043 (-100 2125);
PAINT GREEN (-100 2125);
DISPLAY INVISIBLE (-100 2125);
FORCEPROP 1 LAST HDL_TAP TRUE
J 2
(-425 2050);
DISPLAY 1.234043 (-425 2050);
PAINT GREEN (-425 2050);
DISPLAY INVISIBLE (-425 2050);
FORCEPROP 1 LAST PATH I67
J 2
(-98 2175);
DISPLAY 0.872340 (-98 2175);
PAINT GREEN (-98 2175);
DISPLAY INVISIBLE (-98 2175);
FORCEADD TAP..6
R 2
(-100 2075);
FORCEPROP 3 LASTPIN (-150 2075) SIG_NAME M_K_DQ<15>
J 0
(-140 2085);
DISPLAY 0.659574 (-140 2085);
PAINT MONO (-140 2085);
DISPLAY INVISIBLE (-140 2085);
FORCEPROP 1 LASTPIN (-150 2075) BN 15
J 2
(-100 2085);
DISPLAY 0.617021 (-100 2085);
PAINT PINK (-100 2085);
FORCEPROP 2 LAST CDS_LIB mstr_standard
J 2
(-100 2075);
DISPLAY 0.787234 (-100 2075);
PAINT MONO (-100 2075);
DISPLAY INVISIBLE (-100 2075);
FORCEPROP 1 LAST BODY_TYPE PLUMBING
J 2
(-100 2025);
DISPLAY 1.234043 (-100 2025);
PAINT GREEN (-100 2025);
DISPLAY INVISIBLE (-100 2025);
FORCEPROP 1 LAST HDL_TAP TRUE
J 2
(-425 1950);
DISPLAY 1.234043 (-425 1950);
PAINT GREEN (-425 1950);
DISPLAY INVISIBLE (-425 1950);
FORCEPROP 1 LAST PATH I68
J 2
(-98 2075);
DISPLAY 0.872340 (-98 2075);
PAINT GREEN (-98 2075);
DISPLAY INVISIBLE (-98 2075);
FORCEADD TAP..6
R 2
(-100 2275);
FORCEPROP 3 LASTPIN (-150 2275) SIG_NAME M_K_DQ<19>
J 0
(-140 2285);
DISPLAY 0.659574 (-140 2285);
PAINT MONO (-140 2285);
DISPLAY INVISIBLE (-140 2285);
FORCEPROP 1 LASTPIN (-150 2275) BN 19
J 2
(-100 2285);
DISPLAY 0.617021 (-100 2285);
PAINT PINK (-100 2285);
FORCEPROP 2 LAST CDS_LIB mstr_standard
J 2
(-100 2275);
DISPLAY 0.787234 (-100 2275);
PAINT MONO (-100 2275);
DISPLAY INVISIBLE (-100 2275);
FORCEPROP 1 LAST BODY_TYPE PLUMBING
J 2
(-100 2225);
DISPLAY 1.234043 (-100 2225);
PAINT GREEN (-100 2225);
DISPLAY INVISIBLE (-100 2225);
FORCEPROP 1 LAST HDL_TAP TRUE
J 2
(-425 2150);
DISPLAY 1.234043 (-425 2150);
PAINT GREEN (-425 2150);
DISPLAY INVISIBLE (-425 2150);
FORCEPROP 1 LAST PATH I69
J 2
(-98 2275);
DISPLAY 0.872340 (-98 2275);
PAINT GREEN (-98 2275);
DISPLAY INVISIBLE (-98 2275);
FORCEADD OFFPAGE..1
(-2400 1775);
FORCEPROP 2 LAST $XR0 60 
J 0
(-2651 1775);
DISPLAY 0.638298 (-2651 1775);
PAINT MONO (-2651 1775);
FORCEPROP 2 LAST $XR1 83 
J 0
(-2741 1775);
DISPLAY 0.638298 (-2741 1775);
PAINT MONO (-2741 1775);
FORCEPROP 2 LAST CDS_LIB mstr_standard
J 0
(-2400 1775);
DISPLAY 0.787234 (-2400 1775);
PAINT MONO (-2400 1775);
DISPLAY INVISIBLE (-2400 1775);
FORCEPROP 1 LAST OFFPAGE TRUE
J 0
(-2075 1650);
DISPLAY 0.936170 (-2075 1650);
PAINT GREEN (-2075 1650);
DISPLAY INVISIBLE (-2075 1650);
FORCEPROP 1 LAST COMMENT_BODY TRUE
J 0
(-2275 1675);
DISPLAY 0.936170 (-2275 1675);
PAINT GREEN (-2275 1675);
DISPLAY INVISIBLE (-2275 1675);
FORCEPROP 2 LAST PATH I7
J 0
(-2650 1825);
DISPLAY 1.021277 (-2650 1825);
PAINT ORANGE (-2650 1825);
DISPLAY INVISIBLE (-2650 1825);
FORCEADD TAP..6
R 2
(-100 2225);
FORCEPROP 3 LASTPIN (-150 2225) SIG_NAME M_K_DQ<18>
J 0
(-140 2235);
DISPLAY 0.659574 (-140 2235);
PAINT MONO (-140 2235);
DISPLAY INVISIBLE (-140 2235);
FORCEPROP 1 LASTPIN (-150 2225) BN 18
J 2
(-100 2235);
DISPLAY 0.617021 (-100 2235);
PAINT PINK (-100 2235);
FORCEPROP 2 LAST CDS_LIB mstr_standard
J 2
(-100 2225);
DISPLAY 0.787234 (-100 2225);
PAINT MONO (-100 2225);
DISPLAY INVISIBLE (-100 2225);
FORCEPROP 1 LAST BODY_TYPE PLUMBING
J 2
(-100 2175);
DISPLAY 1.234043 (-100 2175);
PAINT GREEN (-100 2175);
DISPLAY INVISIBLE (-100 2175);
FORCEPROP 1 LAST HDL_TAP TRUE
J 2
(-425 2100);
DISPLAY 1.234043 (-425 2100);
PAINT GREEN (-425 2100);
DISPLAY INVISIBLE (-425 2100);
FORCEPROP 1 LAST PATH I70
J 2
(-98 2225);
DISPLAY 0.872340 (-98 2225);
PAINT GREEN (-98 2225);
DISPLAY INVISIBLE (-98 2225);
FORCEADD TAP..6
R 2
(-100 2425);
FORCEPROP 3 LASTPIN (-150 2425) SIG_NAME M_K_DQ<22>
J 0
(-140 2435);
DISPLAY 0.659574 (-140 2435);
PAINT MONO (-140 2435);
DISPLAY INVISIBLE (-140 2435);
FORCEPROP 1 LASTPIN (-150 2425) BN 22
J 2
(-100 2435);
DISPLAY 0.617021 (-100 2435);
PAINT PINK (-100 2435);
FORCEPROP 2 LAST CDS_LIB mstr_standard
J 2
(-100 2425);
DISPLAY 0.787234 (-100 2425);
PAINT MONO (-100 2425);
DISPLAY INVISIBLE (-100 2425);
FORCEPROP 1 LAST BODY_TYPE PLUMBING
J 2
(-100 2375);
DISPLAY 1.234043 (-100 2375);
PAINT GREEN (-100 2375);
DISPLAY INVISIBLE (-100 2375);
FORCEPROP 1 LAST HDL_TAP TRUE
J 2
(-425 2300);
DISPLAY 1.234043 (-425 2300);
PAINT GREEN (-425 2300);
DISPLAY INVISIBLE (-425 2300);
FORCEPROP 1 LAST PATH I71
J 2
(-98 2425);
DISPLAY 0.872340 (-98 2425);
PAINT GREEN (-98 2425);
DISPLAY INVISIBLE (-98 2425);
FORCEADD TAP..6
R 2
(-100 2375);
FORCEPROP 3 LASTPIN (-150 2375) SIG_NAME M_K_DQ<21>
J 0
(-140 2385);
DISPLAY 0.659574 (-140 2385);
PAINT MONO (-140 2385);
DISPLAY INVISIBLE (-140 2385);
FORCEPROP 1 LASTPIN (-150 2375) BN 21
J 2
(-100 2385);
DISPLAY 0.617021 (-100 2385);
PAINT PINK (-100 2385);
FORCEPROP 2 LAST CDS_LIB mstr_standard
J 2
(-100 2375);
DISPLAY 0.787234 (-100 2375);
PAINT MONO (-100 2375);
DISPLAY INVISIBLE (-100 2375);
FORCEPROP 1 LAST BODY_TYPE PLUMBING
J 2
(-100 2325);
DISPLAY 1.234043 (-100 2325);
PAINT GREEN (-100 2325);
DISPLAY INVISIBLE (-100 2325);
FORCEPROP 1 LAST HDL_TAP TRUE
J 2
(-425 2250);
DISPLAY 1.234043 (-425 2250);
PAINT GREEN (-425 2250);
DISPLAY INVISIBLE (-425 2250);
FORCEPROP 1 LAST PATH I72
J 2
(-98 2375);
DISPLAY 0.872340 (-98 2375);
PAINT GREEN (-98 2375);
DISPLAY INVISIBLE (-98 2375);
FORCEADD TAP..6
R 2
(-100 2325);
FORCEPROP 3 LASTPIN (-150 2325) SIG_NAME M_K_DQ<20>
J 0
(-140 2335);
DISPLAY 0.659574 (-140 2335);
PAINT MONO (-140 2335);
DISPLAY INVISIBLE (-140 2335);
FORCEPROP 1 LASTPIN (-150 2325) BN 20
J 2
(-100 2335);
DISPLAY 0.617021 (-100 2335);
PAINT PINK (-100 2335);
FORCEPROP 2 LAST CDS_LIB mstr_standard
J 2
(-100 2325);
DISPLAY 0.787234 (-100 2325);
PAINT MONO (-100 2325);
DISPLAY INVISIBLE (-100 2325);
FORCEPROP 1 LAST BODY_TYPE PLUMBING
J 2
(-100 2275);
DISPLAY 1.234043 (-100 2275);
PAINT GREEN (-100 2275);
DISPLAY INVISIBLE (-100 2275);
FORCEPROP 1 LAST HDL_TAP TRUE
J 2
(-425 2200);
DISPLAY 1.234043 (-425 2200);
PAINT GREEN (-425 2200);
DISPLAY INVISIBLE (-425 2200);
FORCEPROP 1 LAST PATH I73
J 2
(-98 2325);
DISPLAY 0.872340 (-98 2325);
PAINT GREEN (-98 2325);
DISPLAY INVISIBLE (-98 2325);
FORCEADD TAP..6
R 2
(-100 2475);
FORCEPROP 3 LASTPIN (-150 2475) SIG_NAME M_K_DQ<23>
J 0
(-140 2485);
DISPLAY 0.659574 (-140 2485);
PAINT MONO (-140 2485);
DISPLAY INVISIBLE (-140 2485);
FORCEPROP 1 LASTPIN (-150 2475) BN 23
J 2
(-100 2485);
DISPLAY 0.617021 (-100 2485);
PAINT PINK (-100 2485);
FORCEPROP 2 LAST CDS_LIB mstr_standard
J 2
(-100 2475);
DISPLAY 0.787234 (-100 2475);
PAINT MONO (-100 2475);
DISPLAY INVISIBLE (-100 2475);
FORCEPROP 1 LAST BODY_TYPE PLUMBING
J 2
(-100 2425);
DISPLAY 1.234043 (-100 2425);
PAINT GREEN (-100 2425);
DISPLAY INVISIBLE (-100 2425);
FORCEPROP 1 LAST HDL_TAP TRUE
J 2
(-425 2350);
DISPLAY 1.234043 (-425 2350);
PAINT GREEN (-425 2350);
DISPLAY INVISIBLE (-425 2350);
FORCEPROP 1 LAST PATH I74
J 2
(-98 2475);
DISPLAY 0.872340 (-98 2475);
PAINT GREEN (-98 2475);
DISPLAY INVISIBLE (-98 2475);
FORCEADD TAP..6
R 2
(-100 2525);
FORCEPROP 3 LASTPIN (-150 2525) SIG_NAME M_K_DQ<24>
J 0
(-140 2535);
DISPLAY 0.659574 (-140 2535);
PAINT MONO (-140 2535);
DISPLAY INVISIBLE (-140 2535);
FORCEPROP 1 LASTPIN (-150 2525) BN 24
J 2
(-100 2535);
DISPLAY 0.617021 (-100 2535);
PAINT PINK (-100 2535);
FORCEPROP 2 LAST CDS_LIB mstr_standard
J 2
(-100 2525);
DISPLAY 0.787234 (-100 2525);
PAINT MONO (-100 2525);
DISPLAY INVISIBLE (-100 2525);
FORCEPROP 1 LAST BODY_TYPE PLUMBING
J 2
(-100 2475);
DISPLAY 1.234043 (-100 2475);
PAINT GREEN (-100 2475);
DISPLAY INVISIBLE (-100 2475);
FORCEPROP 1 LAST HDL_TAP TRUE
J 2
(-425 2400);
DISPLAY 1.234043 (-425 2400);
PAINT GREEN (-425 2400);
DISPLAY INVISIBLE (-425 2400);
FORCEPROP 1 LAST PATH I75
J 2
(-98 2525);
DISPLAY 0.872340 (-98 2525);
PAINT GREEN (-98 2525);
DISPLAY INVISIBLE (-98 2525);
FORCEADD TAP..6
R 2
(-100 2675);
FORCEPROP 3 LASTPIN (-150 2675) SIG_NAME M_K_DQ<27>
J 0
(-140 2685);
DISPLAY 0.659574 (-140 2685);
PAINT MONO (-140 2685);
DISPLAY INVISIBLE (-140 2685);
FORCEPROP 1 LASTPIN (-150 2675) BN 27
J 2
(-100 2685);
DISPLAY 0.617021 (-100 2685);
PAINT PINK (-100 2685);
FORCEPROP 2 LAST CDS_LIB mstr_standard
J 2
(-100 2675);
DISPLAY 0.787234 (-100 2675);
PAINT MONO (-100 2675);
DISPLAY INVISIBLE (-100 2675);
FORCEPROP 1 LAST BODY_TYPE PLUMBING
J 2
(-100 2625);
DISPLAY 1.234043 (-100 2625);
PAINT GREEN (-100 2625);
DISPLAY INVISIBLE (-100 2625);
FORCEPROP 1 LAST HDL_TAP TRUE
J 2
(-425 2550);
DISPLAY 1.234043 (-425 2550);
PAINT GREEN (-425 2550);
DISPLAY INVISIBLE (-425 2550);
FORCEPROP 1 LAST PATH I76
J 2
(-98 2675);
DISPLAY 0.872340 (-98 2675);
PAINT GREEN (-98 2675);
DISPLAY INVISIBLE (-98 2675);
FORCEADD TAP..6
R 2
(-100 2625);
FORCEPROP 3 LASTPIN (-150 2625) SIG_NAME M_K_DQ<26>
J 0
(-140 2635);
DISPLAY 0.659574 (-140 2635);
PAINT MONO (-140 2635);
DISPLAY INVISIBLE (-140 2635);
FORCEPROP 1 LASTPIN (-150 2625) BN 26
J 2
(-100 2635);
DISPLAY 0.617021 (-100 2635);
PAINT PINK (-100 2635);
FORCEPROP 2 LAST CDS_LIB mstr_standard
J 2
(-100 2625);
DISPLAY 0.787234 (-100 2625);
PAINT MONO (-100 2625);
DISPLAY INVISIBLE (-100 2625);
FORCEPROP 1 LAST BODY_TYPE PLUMBING
J 2
(-100 2575);
DISPLAY 1.234043 (-100 2575);
PAINT GREEN (-100 2575);
DISPLAY INVISIBLE (-100 2575);
FORCEPROP 1 LAST HDL_TAP TRUE
J 2
(-425 2500);
DISPLAY 1.234043 (-425 2500);
PAINT GREEN (-425 2500);
DISPLAY INVISIBLE (-425 2500);
FORCEPROP 1 LAST PATH I77
J 2
(-98 2625);
DISPLAY 0.872340 (-98 2625);
PAINT GREEN (-98 2625);
DISPLAY INVISIBLE (-98 2625);
FORCEADD TAP..6
R 2
(-100 2575);
FORCEPROP 3 LASTPIN (-150 2575) SIG_NAME M_K_DQ<25>
J 0
(-140 2585);
DISPLAY 0.659574 (-140 2585);
PAINT MONO (-140 2585);
DISPLAY INVISIBLE (-140 2585);
FORCEPROP 1 LASTPIN (-150 2575) BN 25
J 2
(-100 2585);
DISPLAY 0.617021 (-100 2585);
PAINT PINK (-100 2585);
FORCEPROP 2 LAST CDS_LIB mstr_standard
J 2
(-100 2575);
DISPLAY 0.787234 (-100 2575);
PAINT MONO (-100 2575);
DISPLAY INVISIBLE (-100 2575);
FORCEPROP 1 LAST BODY_TYPE PLUMBING
J 2
(-100 2525);
DISPLAY 1.234043 (-100 2525);
PAINT GREEN (-100 2525);
DISPLAY INVISIBLE (-100 2525);
FORCEPROP 1 LAST HDL_TAP TRUE
J 2
(-425 2450);
DISPLAY 1.234043 (-425 2450);
PAINT GREEN (-425 2450);
DISPLAY INVISIBLE (-425 2450);
FORCEPROP 1 LAST PATH I78
J 2
(-98 2575);
DISPLAY 0.872340 (-98 2575);
PAINT GREEN (-98 2575);
DISPLAY INVISIBLE (-98 2575);
FORCEADD PVDDQ_KLM..1
(325 2275);
FORCEPROP 3 LASTPIN (325 2225) SIG_NAME PVDDQ_KLM\g
J 0
(335 2235);
DISPLAY 0.659574 (335 2235);
PAINT MONO (335 2235);
DISPLAY INVISIBLE (335 2235);
FORCEPROP 1 LAST VOLTAGE 1.2V
J 0
(280 2232);
DISPLAY 0.340426 (280 2232);
PAINT SKYBLUE (280 2232);
DISPLAY INVISIBLE (280 2232);
FORCEPROP 2 LAST BOM_COST MEM
J 0
(325 2280);
PAINT ORANGE (325 2280);
DISPLAY INVISIBLE (325 2280);
FORCEPROP 2 LAST CDS_LIB mstr_symbols
J 0
(325 2275);
PAINT ORANGE (325 2275);
DISPLAY INVISIBLE (325 2275);
FORCEPROP 1 LAST BODY_TYPE PLUMBING
J 0
(280 2232);
DISPLAY 0.340426 (280 2232);
PAINT GREEN (280 2232);
DISPLAY INVISIBLE (280 2232);
FORCEPROP 1 LAST PATH I79
J 0
(375 2300);
DISPLAY 0.872340 (375 2300);
PAINT AQUA (375 2300);
DISPLAY INVISIBLE (375 2300);
FORCEPROP 2 LAST ROOM DDR4_CH_C
J 0
(325 2375);
DISPLAY 0.787234 (325 2375);
PAINT ORANGE (325 2375);
DISPLAY INVISIBLE (325 2375);
FORCEPROP 1 LAST HDL_POWER PVDDQ_KLM
J 1
(325 2325);
DISPLAY 0.872340 (325 2325);
PAINT GREEN (325 2325);
DISPLAY INVISIBLE (325 2325);
FORCEADD OFFPAGE..5
(-2575 2175);
FORCEPROP 2 LAST $XR0 43 
J 0
(-2829 2175);
DISPLAY 0.638298 (-2829 2175);
PAINT MONO (-2829 2175);
FORCEPROP 2 LAST $XR1 44 
J 0
(-2919 2175);
DISPLAY 0.638298 (-2919 2175);
PAINT MONO (-2919 2175);
FORCEPROP 2 LAST $XR2 45 
J 0
(-3009 2175);
DISPLAY 0.638298 (-3009 2175);
PAINT MONO (-3009 2175);
FORCEPROP 2 LAST $XR3 46 
J 0
(-3099 2175);
DISPLAY 0.638298 (-3099 2175);
PAINT MONO (-3099 2175);
FORCEPROP 2 LAST $XR4 47 
J 0
(-3189 2175);
DISPLAY 0.638298 (-3189 2175);
PAINT MONO (-3189 2175);
FORCEPROP 2 LAST $XR5 48 
J 0
(-3279 2175);
DISPLAY 0.638298 (-3279 2175);
PAINT MONO (-3279 2175);
FORCEPROP 2 LAST $XR6 49 
J 0
(-3369 2175);
DISPLAY 0.638298 (-3369 2175);
PAINT MONO (-3369 2175);
FORCEPROP 2 LAST $XR7 50 
J 0
(-3459 2175);
DISPLAY 0.638298 (-3459 2175);
PAINT MONO (-3459 2175);
FORCEPROP 2 LAST $XR8 51 
J 0
(-3549 2175);
DISPLAY 0.638298 (-3549 2175);
PAINT MONO (-3549 2175);
FORCEPROP 2 LAST $XR9 52 
J 0
(-3639 2175);
DISPLAY 0.638298 (-3639 2175);
PAINT MONO (-3639 2175);
FORCEPROP 2 LAST $XR10 53 
J 0
(-2829 2139);
DISPLAY 0.638298 (-2829 2139);
PAINT MONO (-2829 2139);
FORCEPROP 2 LAST $XR11 54 
J 0
(-2919 2139);
DISPLAY 0.638298 (-2919 2139);
PAINT MONO (-2919 2139);
FORCEPROP 2 LAST $XR12 77 
J 0
(-3009 2139);
DISPLAY 0.638298 (-3009 2139);
PAINT MONO (-3009 2139);
FORCEPROP 2 LAST $XR13 78 
J 0
(-3099 2139);
DISPLAY 0.638298 (-3099 2139);
PAINT MONO (-3099 2139);
FORCEPROP 2 LAST $XR14 79 
J 0
(-3189 2139);
DISPLAY 0.638298 (-3189 2139);
PAINT MONO (-3189 2139);
FORCEPROP 2 LAST $XR15 80 
J 0
(-3279 2139);
DISPLAY 0.638298 (-3279 2139);
PAINT MONO (-3279 2139);
FORCEPROP 2 LAST $XR16 81 
J 0
(-3369 2139);
DISPLAY 0.638298 (-3369 2139);
PAINT MONO (-3369 2139);
FORCEPROP 2 LAST $XR17 82 
J 0
(-3459 2139);
DISPLAY 0.638298 (-3459 2139);
PAINT MONO (-3459 2139);
FORCEPROP 2 LAST $XR18 83 
J 0
(-3549 2139);
DISPLAY 0.638298 (-3549 2139);
PAINT MONO (-3549 2139);
FORCEPROP 2 LAST $XR19 85 
J 0
(-2829 2211);
DISPLAY 0.638298 (-2829 2211);
PAINT MONO (-2829 2211);
FORCEPROP 2 LAST $XR20 86 
J 0
(-2919 2211);
DISPLAY 0.638298 (-2919 2211);
PAINT MONO (-2919 2211);
FORCEPROP 2 LAST $XR21 87 
J 0
(-3009 2211);
DISPLAY 0.638298 (-3009 2211);
PAINT MONO (-3009 2211);
FORCEPROP 2 LAST $XR22 88 
J 0
(-3099 2211);
DISPLAY 0.638298 (-3099 2211);
PAINT MONO (-3099 2211);
FORCEPROP 2 LAST $XR23 94 
J 0
(-3189 2211);
DISPLAY 0.638298 (-3189 2211);
PAINT MONO (-3189 2211);
FORCEPROP 2 LAST CDS_LIB mstr_standard
J 0
(-2575 2175);
DISPLAY 0.787234 (-2575 2175);
PAINT MONO (-2575 2175);
DISPLAY INVISIBLE (-2575 2175);
FORCEPROP 1 LAST OFFPAGE TRUE
J 0
(-2250 2050);
DISPLAY 1.404255 (-2250 2050);
PAINT GREEN (-2250 2050);
DISPLAY INVISIBLE (-2250 2050);
FORCEPROP 1 LAST COMMENT_BODY TRUE
J 0
(-2475 2100);
DISPLAY 1.404255 (-2475 2100);
PAINT GREEN (-2475 2100);
DISPLAY INVISIBLE (-2475 2100);
FORCEPROP 2 LAST PATH I8
J 0
(-2825 2225);
DISPLAY 1.021277 (-2825 2225);
PAINT ORANGE (-2825 2225);
DISPLAY INVISIBLE (-2825 2225);
FORCEADD TAP..6
R 2
(-100 2725);
FORCEPROP 3 LASTPIN (-150 2725) SIG_NAME M_K_DQ<28>
J 0
(-140 2735);
DISPLAY 0.659574 (-140 2735);
PAINT MONO (-140 2735);
DISPLAY INVISIBLE (-140 2735);
FORCEPROP 1 LASTPIN (-150 2725) BN 28
J 2
(-100 2735);
DISPLAY 0.617021 (-100 2735);
PAINT PINK (-100 2735);
FORCEPROP 2 LAST CDS_LIB mstr_standard
J 2
(-100 2725);
DISPLAY 0.787234 (-100 2725);
PAINT MONO (-100 2725);
DISPLAY INVISIBLE (-100 2725);
FORCEPROP 1 LAST BODY_TYPE PLUMBING
J 2
(-100 2675);
DISPLAY 1.234043 (-100 2675);
PAINT GREEN (-100 2675);
DISPLAY INVISIBLE (-100 2675);
FORCEPROP 1 LAST HDL_TAP TRUE
J 2
(-425 2600);
DISPLAY 1.234043 (-425 2600);
PAINT GREEN (-425 2600);
DISPLAY INVISIBLE (-425 2600);
FORCEPROP 1 LAST PATH I80
J 2
(-98 2725);
DISPLAY 0.872340 (-98 2725);
PAINT GREEN (-98 2725);
DISPLAY INVISIBLE (-98 2725);
FORCEADD TAP..6
R 2
(-100 2775);
FORCEPROP 3 LASTPIN (-150 2775) SIG_NAME M_K_DQ<29>
J 0
(-140 2785);
DISPLAY 0.659574 (-140 2785);
PAINT MONO (-140 2785);
DISPLAY INVISIBLE (-140 2785);
FORCEPROP 1 LASTPIN (-150 2775) BN 29
J 2
(-100 2785);
DISPLAY 0.617021 (-100 2785);
PAINT PINK (-100 2785);
FORCEPROP 2 LAST CDS_LIB mstr_standard
J 2
(-100 2775);
DISPLAY 0.787234 (-100 2775);
PAINT MONO (-100 2775);
DISPLAY INVISIBLE (-100 2775);
FORCEPROP 1 LAST BODY_TYPE PLUMBING
J 2
(-100 2725);
DISPLAY 1.234043 (-100 2725);
PAINT GREEN (-100 2725);
DISPLAY INVISIBLE (-100 2725);
FORCEPROP 1 LAST HDL_TAP TRUE
J 2
(-425 2650);
DISPLAY 1.234043 (-425 2650);
PAINT GREEN (-425 2650);
DISPLAY INVISIBLE (-425 2650);
FORCEPROP 1 LAST PATH I81
J 2
(-98 2775);
DISPLAY 0.872340 (-98 2775);
PAINT GREEN (-98 2775);
DISPLAY INVISIBLE (-98 2775);
FORCEADD TAP..6
R 2
(-100 2825);
FORCEPROP 3 LASTPIN (-150 2825) SIG_NAME M_K_DQ<30>
J 0
(-140 2835);
DISPLAY 0.659574 (-140 2835);
PAINT MONO (-140 2835);
DISPLAY INVISIBLE (-140 2835);
FORCEPROP 1 LASTPIN (-150 2825) BN 30
J 2
(-100 2835);
DISPLAY 0.617021 (-100 2835);
PAINT PINK (-100 2835);
FORCEPROP 2 LAST CDS_LIB mstr_standard
J 2
(-100 2825);
DISPLAY 0.787234 (-100 2825);
PAINT MONO (-100 2825);
DISPLAY INVISIBLE (-100 2825);
FORCEPROP 1 LAST BODY_TYPE PLUMBING
J 2
(-100 2775);
DISPLAY 1.234043 (-100 2775);
PAINT GREEN (-100 2775);
DISPLAY INVISIBLE (-100 2775);
FORCEPROP 1 LAST HDL_TAP TRUE
J 2
(-425 2700);
DISPLAY 1.234043 (-425 2700);
PAINT GREEN (-425 2700);
DISPLAY INVISIBLE (-425 2700);
FORCEPROP 1 LAST PATH I82
J 2
(-98 2825);
DISPLAY 0.872340 (-98 2825);
PAINT GREEN (-98 2825);
DISPLAY INVISIBLE (-98 2825);
FORCEADD TAP..6
R 2
(-100 2875);
FORCEPROP 3 LASTPIN (-150 2875) SIG_NAME M_K_DQ<31>
J 0
(-140 2885);
DISPLAY 0.659574 (-140 2885);
PAINT MONO (-140 2885);
DISPLAY INVISIBLE (-140 2885);
FORCEPROP 1 LASTPIN (-150 2875) BN 31
J 2
(-100 2885);
DISPLAY 0.617021 (-100 2885);
PAINT PINK (-100 2885);
FORCEPROP 2 LAST CDS_LIB mstr_standard
J 2
(-100 2875);
DISPLAY 0.787234 (-100 2875);
PAINT MONO (-100 2875);
DISPLAY INVISIBLE (-100 2875);
FORCEPROP 1 LAST BODY_TYPE PLUMBING
J 2
(-100 2825);
DISPLAY 1.234043 (-100 2825);
PAINT GREEN (-100 2825);
DISPLAY INVISIBLE (-100 2825);
FORCEPROP 1 LAST HDL_TAP TRUE
J 2
(-425 2750);
DISPLAY 1.234043 (-425 2750);
PAINT GREEN (-425 2750);
DISPLAY INVISIBLE (-425 2750);
FORCEPROP 1 LAST PATH I83
J 2
(-98 2875);
DISPLAY 0.872340 (-98 2875);
PAINT GREEN (-98 2875);
DISPLAY INVISIBLE (-98 2875);
FORCEADD TAP..6
R 2
(-100 2925);
FORCEPROP 3 LASTPIN (-150 2925) SIG_NAME M_K_DQ<32>
J 0
(-140 2935);
DISPLAY 0.659574 (-140 2935);
PAINT MONO (-140 2935);
DISPLAY INVISIBLE (-140 2935);
FORCEPROP 1 LASTPIN (-150 2925) BN 32
J 2
(-100 2935);
DISPLAY 0.617021 (-100 2935);
PAINT PINK (-100 2935);
FORCEPROP 2 LAST CDS_LIB mstr_standard
J 2
(-100 2925);
DISPLAY 0.787234 (-100 2925);
PAINT MONO (-100 2925);
DISPLAY INVISIBLE (-100 2925);
FORCEPROP 1 LAST BODY_TYPE PLUMBING
J 2
(-100 2875);
DISPLAY 1.234043 (-100 2875);
PAINT GREEN (-100 2875);
DISPLAY INVISIBLE (-100 2875);
FORCEPROP 1 LAST HDL_TAP TRUE
J 2
(-425 2800);
DISPLAY 1.234043 (-425 2800);
PAINT GREEN (-425 2800);
DISPLAY INVISIBLE (-425 2800);
FORCEPROP 1 LAST PATH I84
J 2
(-98 2925);
DISPLAY 0.872340 (-98 2925);
PAINT GREEN (-98 2925);
DISPLAY INVISIBLE (-98 2925);
FORCEADD TAP..6
R 2
(-100 2975);
FORCEPROP 3 LASTPIN (-150 2975) SIG_NAME M_K_DQ<33>
J 0
(-140 2985);
DISPLAY 0.659574 (-140 2985);
PAINT MONO (-140 2985);
DISPLAY INVISIBLE (-140 2985);
FORCEPROP 1 LASTPIN (-150 2975) BN 33
J 2
(-100 2985);
DISPLAY 0.617021 (-100 2985);
PAINT PINK (-100 2985);
FORCEPROP 2 LAST CDS_LIB mstr_standard
J 2
(-100 2975);
DISPLAY 0.787234 (-100 2975);
PAINT MONO (-100 2975);
DISPLAY INVISIBLE (-100 2975);
FORCEPROP 1 LAST BODY_TYPE PLUMBING
J 2
(-100 2925);
DISPLAY 1.234043 (-100 2925);
PAINT GREEN (-100 2925);
DISPLAY INVISIBLE (-100 2925);
FORCEPROP 1 LAST HDL_TAP TRUE
J 2
(-425 2850);
DISPLAY 1.234043 (-425 2850);
PAINT GREEN (-425 2850);
DISPLAY INVISIBLE (-425 2850);
FORCEPROP 1 LAST PATH I85
J 2
(-98 2975);
DISPLAY 0.872340 (-98 2975);
PAINT GREEN (-98 2975);
DISPLAY INVISIBLE (-98 2975);
FORCEADD TAP..6
R 2
(-100 3025);
FORCEPROP 3 LASTPIN (-150 3025) SIG_NAME M_K_DQ<34>
J 0
(-140 3035);
DISPLAY 0.659574 (-140 3035);
PAINT MONO (-140 3035);
DISPLAY INVISIBLE (-140 3035);
FORCEPROP 1 LASTPIN (-150 3025) BN 34
J 2
(-100 3035);
DISPLAY 0.617021 (-100 3035);
PAINT PINK (-100 3035);
FORCEPROP 2 LAST CDS_LIB mstr_standard
J 2
(-100 3025);
DISPLAY 0.787234 (-100 3025);
PAINT MONO (-100 3025);
DISPLAY INVISIBLE (-100 3025);
FORCEPROP 1 LAST BODY_TYPE PLUMBING
J 2
(-100 2975);
DISPLAY 1.234043 (-100 2975);
PAINT GREEN (-100 2975);
DISPLAY INVISIBLE (-100 2975);
FORCEPROP 1 LAST HDL_TAP TRUE
J 2
(-425 2900);
DISPLAY 1.234043 (-425 2900);
PAINT GREEN (-425 2900);
DISPLAY INVISIBLE (-425 2900);
FORCEPROP 1 LAST PATH I86
J 2
(-98 3025);
DISPLAY 0.872340 (-98 3025);
PAINT GREEN (-98 3025);
DISPLAY INVISIBLE (-98 3025);
FORCEADD TAP..6
R 2
(-100 3075);
FORCEPROP 3 LASTPIN (-150 3075) SIG_NAME M_K_DQ<35>
J 0
(-140 3085);
DISPLAY 0.659574 (-140 3085);
PAINT MONO (-140 3085);
DISPLAY INVISIBLE (-140 3085);
FORCEPROP 1 LASTPIN (-150 3075) BN 35
J 2
(-100 3085);
DISPLAY 0.617021 (-100 3085);
PAINT PINK (-100 3085);
FORCEPROP 2 LAST CDS_LIB mstr_standard
J 2
(-100 3075);
DISPLAY 0.787234 (-100 3075);
PAINT MONO (-100 3075);
DISPLAY INVISIBLE (-100 3075);
FORCEPROP 1 LAST BODY_TYPE PLUMBING
J 2
(-100 3025);
DISPLAY 1.234043 (-100 3025);
PAINT GREEN (-100 3025);
DISPLAY INVISIBLE (-100 3025);
FORCEPROP 1 LAST HDL_TAP TRUE
J 2
(-425 2950);
DISPLAY 1.234043 (-425 2950);
PAINT GREEN (-425 2950);
DISPLAY INVISIBLE (-425 2950);
FORCEPROP 1 LAST PATH I87
J 2
(-98 3075);
DISPLAY 0.872340 (-98 3075);
PAINT GREEN (-98 3075);
DISPLAY INVISIBLE (-98 3075);
FORCEADD TAP..6
R 2
(-100 3125);
FORCEPROP 3 LASTPIN (-150 3125) SIG_NAME M_K_DQ<36>
J 0
(-140 3135);
DISPLAY 0.659574 (-140 3135);
PAINT MONO (-140 3135);
DISPLAY INVISIBLE (-140 3135);
FORCEPROP 1 LASTPIN (-150 3125) BN 36
J 2
(-100 3135);
DISPLAY 0.617021 (-100 3135);
PAINT PINK (-100 3135);
FORCEPROP 2 LAST CDS_LIB mstr_standard
J 2
(-100 3125);
DISPLAY 0.787234 (-100 3125);
PAINT MONO (-100 3125);
DISPLAY INVISIBLE (-100 3125);
FORCEPROP 1 LAST BODY_TYPE PLUMBING
J 2
(-100 3075);
DISPLAY 1.234043 (-100 3075);
PAINT GREEN (-100 3075);
DISPLAY INVISIBLE (-100 3075);
FORCEPROP 1 LAST HDL_TAP TRUE
J 2
(-425 3000);
DISPLAY 1.234043 (-425 3000);
PAINT GREEN (-425 3000);
DISPLAY INVISIBLE (-425 3000);
FORCEPROP 1 LAST PATH I88
J 2
(-98 3125);
DISPLAY 0.872340 (-98 3125);
PAINT GREEN (-98 3125);
DISPLAY INVISIBLE (-98 3125);
FORCEADD TAP..6
R 2
(-100 3175);
FORCEPROP 3 LASTPIN (-150 3175) SIG_NAME M_K_DQ<37>
J 0
(-140 3185);
DISPLAY 0.659574 (-140 3185);
PAINT MONO (-140 3185);
DISPLAY INVISIBLE (-140 3185);
FORCEPROP 1 LASTPIN (-150 3175) BN 37
J 2
(-100 3185);
DISPLAY 0.617021 (-100 3185);
PAINT PINK (-100 3185);
FORCEPROP 2 LAST CDS_LIB mstr_standard
J 2
(-100 3175);
DISPLAY 0.787234 (-100 3175);
PAINT MONO (-100 3175);
DISPLAY INVISIBLE (-100 3175);
FORCEPROP 1 LAST BODY_TYPE PLUMBING
J 2
(-100 3125);
DISPLAY 1.234043 (-100 3125);
PAINT GREEN (-100 3125);
DISPLAY INVISIBLE (-100 3125);
FORCEPROP 1 LAST HDL_TAP TRUE
J 2
(-425 3050);
DISPLAY 1.234043 (-425 3050);
PAINT GREEN (-425 3050);
DISPLAY INVISIBLE (-425 3050);
FORCEPROP 1 LAST PATH I89
J 2
(-98 3175);
DISPLAY 0.872340 (-98 3175);
PAINT GREEN (-98 3175);
DISPLAY INVISIBLE (-98 3175);
FORCEADD OFFPAGE..1
(-2650 3375);
FORCEPROP 2 LAST $XR0 60 
J 0
(-2901 3375);
DISPLAY 0.638298 (-2901 3375);
PAINT MONO (-2901 3375);
FORCEPROP 2 LAST $XR1 83 
J 0
(-2991 3375);
DISPLAY 0.638298 (-2991 3375);
PAINT MONO (-2991 3375);
FORCEPROP 2 LAST CDS_LIB mstr_standard
J 0
(-2650 3375);
DISPLAY 0.787234 (-2650 3375);
PAINT MONO (-2650 3375);
DISPLAY INVISIBLE (-2650 3375);
FORCEPROP 1 LAST OFFPAGE TRUE
J 0
(-2325 3250);
DISPLAY 0.936170 (-2325 3250);
PAINT GREEN (-2325 3250);
DISPLAY INVISIBLE (-2325 3250);
FORCEPROP 1 LAST COMMENT_BODY TRUE
J 0
(-2525 3275);
DISPLAY 0.936170 (-2525 3275);
PAINT GREEN (-2525 3275);
DISPLAY INVISIBLE (-2525 3275);
FORCEPROP 2 LAST PATH I9
J 0
(-2900 3425);
DISPLAY 1.021277 (-2900 3425);
PAINT ORANGE (-2900 3425);
DISPLAY INVISIBLE (-2900 3425);
FORCEADD TAP..6
R 2
(-100 3225);
FORCEPROP 3 LASTPIN (-150 3225) SIG_NAME M_K_DQ<38>
J 0
(-140 3235);
DISPLAY 0.659574 (-140 3235);
PAINT MONO (-140 3235);
DISPLAY INVISIBLE (-140 3235);
FORCEPROP 1 LASTPIN (-150 3225) BN 38
J 2
(-100 3235);
DISPLAY 0.617021 (-100 3235);
PAINT PINK (-100 3235);
FORCEPROP 2 LAST CDS_LIB mstr_standard
J 2
(-100 3225);
DISPLAY 0.787234 (-100 3225);
PAINT MONO (-100 3225);
DISPLAY INVISIBLE (-100 3225);
FORCEPROP 1 LAST BODY_TYPE PLUMBING
J 2
(-100 3175);
DISPLAY 1.234043 (-100 3175);
PAINT GREEN (-100 3175);
DISPLAY INVISIBLE (-100 3175);
FORCEPROP 1 LAST HDL_TAP TRUE
J 2
(-425 3100);
DISPLAY 1.234043 (-425 3100);
PAINT GREEN (-425 3100);
DISPLAY INVISIBLE (-425 3100);
FORCEPROP 1 LAST PATH I90
J 2
(-98 3225);
DISPLAY 0.872340 (-98 3225);
PAINT GREEN (-98 3225);
DISPLAY INVISIBLE (-98 3225);
FORCEADD TAP..6
R 2
(-100 3325);
FORCEPROP 3 LASTPIN (-150 3325) SIG_NAME M_K_DQ<40>
J 0
(-140 3335);
DISPLAY 0.659574 (-140 3335);
PAINT MONO (-140 3335);
DISPLAY INVISIBLE (-140 3335);
FORCEPROP 1 LASTPIN (-150 3325) BN 40
J 2
(-100 3335);
DISPLAY 0.617021 (-100 3335);
PAINT PINK (-100 3335);
FORCEPROP 2 LAST CDS_LIB mstr_standard
J 2
(-100 3325);
DISPLAY 0.787234 (-100 3325);
PAINT MONO (-100 3325);
DISPLAY INVISIBLE (-100 3325);
FORCEPROP 1 LAST BODY_TYPE PLUMBING
J 2
(-100 3275);
DISPLAY 1.234043 (-100 3275);
PAINT GREEN (-100 3275);
DISPLAY INVISIBLE (-100 3275);
FORCEPROP 1 LAST HDL_TAP TRUE
J 2
(-425 3200);
DISPLAY 1.234043 (-425 3200);
PAINT GREEN (-425 3200);
DISPLAY INVISIBLE (-425 3200);
FORCEPROP 1 LAST PATH I91
J 2
(-98 3325);
DISPLAY 0.872340 (-98 3325);
PAINT GREEN (-98 3325);
DISPLAY INVISIBLE (-98 3325);
FORCEADD TAP..6
R 2
(-100 3275);
FORCEPROP 3 LASTPIN (-150 3275) SIG_NAME M_K_DQ<39>
J 0
(-140 3285);
DISPLAY 0.659574 (-140 3285);
PAINT MONO (-140 3285);
DISPLAY INVISIBLE (-140 3285);
FORCEPROP 1 LASTPIN (-150 3275) BN 39
J 2
(-100 3285);
DISPLAY 0.617021 (-100 3285);
PAINT PINK (-100 3285);
FORCEPROP 2 LAST CDS_LIB mstr_standard
J 2
(-100 3275);
DISPLAY 0.787234 (-100 3275);
PAINT MONO (-100 3275);
DISPLAY INVISIBLE (-100 3275);
FORCEPROP 1 LAST BODY_TYPE PLUMBING
J 2
(-100 3225);
DISPLAY 1.234043 (-100 3225);
PAINT GREEN (-100 3225);
DISPLAY INVISIBLE (-100 3225);
FORCEPROP 1 LAST HDL_TAP TRUE
J 2
(-425 3150);
DISPLAY 1.234043 (-425 3150);
PAINT GREEN (-425 3150);
DISPLAY INVISIBLE (-425 3150);
FORCEPROP 1 LAST PATH I92
J 2
(-98 3275);
DISPLAY 0.872340 (-98 3275);
PAINT GREEN (-98 3275);
DISPLAY INVISIBLE (-98 3275);
FORCEADD TAP..6
R 2
(-100 3425);
FORCEPROP 3 LASTPIN (-150 3425) SIG_NAME M_K_DQ<42>
J 0
(-140 3435);
DISPLAY 0.659574 (-140 3435);
PAINT MONO (-140 3435);
DISPLAY INVISIBLE (-140 3435);
FORCEPROP 1 LASTPIN (-150 3425) BN 42
J 2
(-100 3435);
DISPLAY 0.617021 (-100 3435);
PAINT PINK (-100 3435);
FORCEPROP 2 LAST CDS_LIB mstr_standard
J 2
(-100 3425);
DISPLAY 0.787234 (-100 3425);
PAINT MONO (-100 3425);
DISPLAY INVISIBLE (-100 3425);
FORCEPROP 1 LAST BODY_TYPE PLUMBING
J 2
(-100 3375);
DISPLAY 1.234043 (-100 3375);
PAINT GREEN (-100 3375);
DISPLAY INVISIBLE (-100 3375);
FORCEPROP 1 LAST HDL_TAP TRUE
J 2
(-425 3300);
DISPLAY 1.234043 (-425 3300);
PAINT GREEN (-425 3300);
DISPLAY INVISIBLE (-425 3300);
FORCEPROP 1 LAST PATH I93
J 2
(-98 3425);
DISPLAY 0.872340 (-98 3425);
PAINT GREEN (-98 3425);
DISPLAY INVISIBLE (-98 3425);
FORCEADD TAP..6
R 2
(-100 3375);
FORCEPROP 3 LASTPIN (-150 3375) SIG_NAME M_K_DQ<41>
J 0
(-140 3385);
DISPLAY 0.659574 (-140 3385);
PAINT MONO (-140 3385);
DISPLAY INVISIBLE (-140 3385);
FORCEPROP 1 LASTPIN (-150 3375) BN 41
J 2
(-100 3385);
DISPLAY 0.617021 (-100 3385);
PAINT PINK (-100 3385);
FORCEPROP 2 LAST CDS_LIB mstr_standard
J 2
(-100 3375);
DISPLAY 0.787234 (-100 3375);
PAINT MONO (-100 3375);
DISPLAY INVISIBLE (-100 3375);
FORCEPROP 1 LAST BODY_TYPE PLUMBING
J 2
(-100 3325);
DISPLAY 1.234043 (-100 3325);
PAINT GREEN (-100 3325);
DISPLAY INVISIBLE (-100 3325);
FORCEPROP 1 LAST HDL_TAP TRUE
J 2
(-425 3250);
DISPLAY 1.234043 (-425 3250);
PAINT GREEN (-425 3250);
DISPLAY INVISIBLE (-425 3250);
FORCEPROP 1 LAST PATH I94
J 2
(-98 3375);
DISPLAY 0.872340 (-98 3375);
PAINT GREEN (-98 3375);
DISPLAY INVISIBLE (-98 3375);
FORCEADD TAP..6
R 2
(-100 3475);
FORCEPROP 3 LASTPIN (-150 3475) SIG_NAME M_K_DQ<43>
J 0
(-140 3485);
DISPLAY 0.659574 (-140 3485);
PAINT MONO (-140 3485);
DISPLAY INVISIBLE (-140 3485);
FORCEPROP 1 LASTPIN (-150 3475) BN 43
J 2
(-100 3485);
DISPLAY 0.617021 (-100 3485);
PAINT PINK (-100 3485);
FORCEPROP 2 LAST CDS_LIB mstr_standard
J 2
(-100 3475);
DISPLAY 0.787234 (-100 3475);
PAINT MONO (-100 3475);
DISPLAY INVISIBLE (-100 3475);
FORCEPROP 1 LAST BODY_TYPE PLUMBING
J 2
(-100 3425);
DISPLAY 1.234043 (-100 3425);
PAINT GREEN (-100 3425);
DISPLAY INVISIBLE (-100 3425);
FORCEPROP 1 LAST HDL_TAP TRUE
J 2
(-425 3350);
DISPLAY 1.234043 (-425 3350);
PAINT GREEN (-425 3350);
DISPLAY INVISIBLE (-425 3350);
FORCEPROP 1 LAST PATH I95
J 2
(-98 3475);
DISPLAY 0.872340 (-98 3475);
PAINT GREEN (-98 3475);
DISPLAY INVISIBLE (-98 3475);
FORCEADD TAP..6
R 2
(-100 3575);
FORCEPROP 3 LASTPIN (-150 3575) SIG_NAME M_K_DQ<45>
J 0
(-140 3585);
DISPLAY 0.659574 (-140 3585);
PAINT MONO (-140 3585);
DISPLAY INVISIBLE (-140 3585);
FORCEPROP 1 LASTPIN (-150 3575) BN 45
J 2
(-100 3585);
DISPLAY 0.617021 (-100 3585);
PAINT PINK (-100 3585);
FORCEPROP 2 LAST CDS_LIB mstr_standard
J 2
(-100 3575);
DISPLAY 0.787234 (-100 3575);
PAINT MONO (-100 3575);
DISPLAY INVISIBLE (-100 3575);
FORCEPROP 1 LAST BODY_TYPE PLUMBING
J 2
(-100 3525);
DISPLAY 1.234043 (-100 3525);
PAINT GREEN (-100 3525);
DISPLAY INVISIBLE (-100 3525);
FORCEPROP 1 LAST HDL_TAP TRUE
J 2
(-425 3450);
DISPLAY 1.234043 (-425 3450);
PAINT GREEN (-425 3450);
DISPLAY INVISIBLE (-425 3450);
FORCEPROP 1 LAST PATH I96
J 2
(-98 3575);
DISPLAY 0.872340 (-98 3575);
PAINT GREEN (-98 3575);
DISPLAY INVISIBLE (-98 3575);
FORCEADD TAP..6
R 2
(-100 3525);
FORCEPROP 3 LASTPIN (-150 3525) SIG_NAME M_K_DQ<44>
J 0
(-140 3535);
DISPLAY 0.659574 (-140 3535);
PAINT MONO (-140 3535);
DISPLAY INVISIBLE (-140 3535);
FORCEPROP 1 LASTPIN (-150 3525) BN 44
J 2
(-100 3535);
DISPLAY 0.617021 (-100 3535);
PAINT PINK (-100 3535);
FORCEPROP 2 LAST CDS_LIB mstr_standard
J 2
(-100 3525);
DISPLAY 0.787234 (-100 3525);
PAINT MONO (-100 3525);
DISPLAY INVISIBLE (-100 3525);
FORCEPROP 1 LAST BODY_TYPE PLUMBING
J 2
(-100 3475);
DISPLAY 1.234043 (-100 3475);
PAINT GREEN (-100 3475);
DISPLAY INVISIBLE (-100 3475);
FORCEPROP 1 LAST HDL_TAP TRUE
J 2
(-425 3400);
DISPLAY 1.234043 (-425 3400);
PAINT GREEN (-425 3400);
DISPLAY INVISIBLE (-425 3400);
FORCEPROP 1 LAST PATH I97
J 2
(-98 3525);
DISPLAY 0.872340 (-98 3525);
PAINT GREEN (-98 3525);
DISPLAY INVISIBLE (-98 3525);
FORCEADD TAP..6
R 2
(-100 3675);
FORCEPROP 3 LASTPIN (-150 3675) SIG_NAME M_K_DQ<47>
J 0
(-140 3685);
DISPLAY 0.659574 (-140 3685);
PAINT MONO (-140 3685);
DISPLAY INVISIBLE (-140 3685);
FORCEPROP 1 LASTPIN (-150 3675) BN 47
J 2
(-100 3685);
DISPLAY 0.617021 (-100 3685);
PAINT PINK (-100 3685);
FORCEPROP 2 LAST CDS_LIB mstr_standard
J 2
(-100 3675);
DISPLAY 0.787234 (-100 3675);
PAINT MONO (-100 3675);
DISPLAY INVISIBLE (-100 3675);
FORCEPROP 1 LAST BODY_TYPE PLUMBING
J 2
(-100 3625);
DISPLAY 1.234043 (-100 3625);
PAINT GREEN (-100 3625);
DISPLAY INVISIBLE (-100 3625);
FORCEPROP 1 LAST HDL_TAP TRUE
J 2
(-425 3550);
DISPLAY 1.234043 (-425 3550);
PAINT GREEN (-425 3550);
DISPLAY INVISIBLE (-425 3550);
FORCEPROP 1 LAST PATH I98
J 2
(-98 3675);
DISPLAY 0.872340 (-98 3675);
PAINT GREEN (-98 3675);
DISPLAY INVISIBLE (-98 3675);
FORCEADD TAP..6
R 2
(-100 3625);
FORCEPROP 3 LASTPIN (-150 3625) SIG_NAME M_K_DQ<46>
J 0
(-140 3635);
DISPLAY 0.659574 (-140 3635);
PAINT MONO (-140 3635);
DISPLAY INVISIBLE (-140 3635);
FORCEPROP 1 LASTPIN (-150 3625) BN 46
J 2
(-100 3635);
DISPLAY 0.617021 (-100 3635);
PAINT PINK (-100 3635);
FORCEPROP 2 LAST CDS_LIB mstr_standard
J 2
(-100 3625);
DISPLAY 0.787234 (-100 3625);
PAINT MONO (-100 3625);
DISPLAY INVISIBLE (-100 3625);
FORCEPROP 1 LAST BODY_TYPE PLUMBING
J 2
(-100 3575);
DISPLAY 1.234043 (-100 3575);
PAINT GREEN (-100 3575);
DISPLAY INVISIBLE (-100 3575);
FORCEPROP 1 LAST HDL_TAP TRUE
J 2
(-425 3500);
DISPLAY 1.234043 (-425 3500);
PAINT GREEN (-425 3500);
DISPLAY INVISIBLE (-425 3500);
FORCEPROP 1 LAST PATH I99
J 2
(-98 3625);
DISPLAY 0.872340 (-98 3625);
PAINT GREEN (-98 3625);
DISPLAY INVISIBLE (-98 3625);
FORCEADD BOM_NOTE..1
(-3375 4975);
FORCEPROP 0 LAST L1 UNSTUFF FOR SKU B
J 0
(-3525 4875);
DISPLAY 1.063830 (-3525 4875);
PAINT WHITE (-3525 4875);
FORCEPROP 2 LAST BOM_COST SB
J 0
(-3525 4950);
DISPLAY 1.361702 (-3525 4950);
PAINT ORANGE (-3525 4950);
DISPLAY INVISIBLE (-3525 4950);
FORCEPROP 2 LAST CDS_LIB mstr_symbols
J 0
(-3375 4975);
PAINT ORANGE (-3375 4975);
DISPLAY INVISIBLE (-3375 4975);
FORCEPROP 1 LAST COMMENT_BODY TRUE
J 0
(-3350 5075);
DISPLAY 1.319149 (-3350 5075);
PAINT ORANGE (-3350 5075);
DISPLAY INVISIBLE (-3350 5075);
FORCEPROP 2 LAST ROOM SB_HEADERS
J 0
(-3525 4950);
DISPLAY 1.361702 (-3525 4950);
PAINT ORANGE (-3525 4950);
DISPLAY INVISIBLE (-3525 4950);
FORCEADD INTEL_CORP_BPAGE..1
(4250 200);
FORCEPROP 1 LAST CDS_CON_LAST_MODIFIED Tue Dec 01 11:51:44 2015
J 0
(2825 525);
PAINT ORANGE (2825 525);
DISPLAY INVISIBLE (2825 525);
FORCEPROP 1 LAST CUSTOM_TXT_CDS <CURRENT_DESIGN_SHEET> OF <TOTAL_DESIGN_SHEETS>
J 0
(3750 225);
PAINT GREEN (3750 225);
FORCEPROP 1 LAST CUSTOM_TXT_CDS <CON_LAST_MODIFIED>
J 0
(2325 550);
PAINT GREEN (2325 550);
FORCEPROP 2 LAST CUSTOM_TXT_CDS <XR_PAGE_TITLE>
J 0
(-3640 5450);
DISPLAY 0.638298 (-3640 5450);
PAINT PINK (-3640 5450);
DISPLAY INVISIBLE (-3640 5450);
FORCEPROP 1 LAST SCH_ADDRESS3 Santa Clara, CA 95052-8119
J 0
(275 225);
DISPLAY 0.617021 (275 225);
PAINT GREEN (275 225);
FORCEPROP 1 LAST SCH_ADDRESS2 P.O. BOX 58119
J 0
(275 275);
DISPLAY 0.617021 (275 275);
PAINT GREEN (275 275);
FORCEPROP 1 LAST SCH_ADDRESS1 2200 Mission College Blvd.
J 0
(275 325);
DISPLAY 0.617021 (275 325);
PAINT GREEN (275 325);
FORCEPROP 1 LAST SCH_TITLE CPU1 DDR4 CH K DIMM1
J 0
(-3700 250);
DISPLAY 1.212766 (-3700 250);
PAINT ORANGE (-3700 250);
FORCEPROP 1 LAST SCH_NUMBER H4694802
J 0
(2950 350);
DISPLAY 1.212766 (2950 350);
PAINT YELLOW (2950 350);
FORCEPROP 1 LAST SCH_DEPT BESD
J 1
(-200 300);
DISPLAY 1.212766 (-200 300);
PAINT YELLOW (-200 300);
FORCEPROP 1 LAST SCH_REV 2.420
J 0
(4000 350);
DISPLAY 0.978723 (4000 350);
PAINT YELLOW (4000 350);
FORCEPROP 2 LAST CDS_LIB mstr_symbols
J 0
(4250 200);
PAINT MONO (4250 200);
DISPLAY INVISIBLE (4250 200);
FORCEPROP 2 LAST PAGE_BORDER TRUE
J 0
(-3640 5450);
DISPLAY 0.638298 (-3640 5450);
PAINT PINK (-3640 5450);
DISPLAY INVISIBLE (-3640 5450);
FORCEPROP 1 LAST COMMENT_BODY TRUE
J 0
(4262 212);
DISPLAY 0.468085 (4262 212);
PAINT GREEN (4262 212);
DISPLAY INVISIBLE (4262 212);
FORCEPROP 2 LAST CDS_XR_PAGE_TITLE CR-84 : @BASEBOARD_FAB2_LIB.BASEBOARD_FAB2(SCH_1):PAGE84
J 0
(-3640 5450);
DISPLAY 0.638298 (-3640 5450);
PAINT PINK (-3640 5450);
DISPLAY INVISIBLE (-3640 5450);
WIRE 17 -1 (-2150 3250)(-2150 3325);
WIRE 17 -1 (-2150 3150)(-2150 3250);
WIRE 17 -1 (-2150 3325)(-2600 3325);
FORCEPROP 2 LAST SIG_NAME M_K_CLK_DN<3:0>
J 0
(-2550 3335);
DISPLAY 0.617021 (-2550 3335);
PAINT ORANGE (-2550 3335);
WIRE 17 -1 (-50 1400)(-50 1450);
WIRE 17 -1 (-50 1350)(-50 1400);
WIRE 17 -1 (-50 1450)(-50 1500);
WIRE 17 -1 (-50 1500)(-50 1550);
WIRE 17 -1 (-50 1550)(-50 1600);
WIRE 17 -1 (-50 1600)(-50 1650);
WIRE 17 -1 (-50 1650)(-50 1700);
WIRE 17 -1 (-50 1700)(-50 1750);
WIRE 17 -1 (-50 1750)(-50 1800);
WIRE 17 -1 (-50 1800)(-50 1850);
WIRE 17 -1 (-50 1850)(-50 1900);
WIRE 17 -1 (-50 1900)(-50 1950);
WIRE 17 -1 (-50 1950)(-50 2000);
WIRE 17 -1 (-50 2000)(-50 2050);
WIRE 17 -1 (-50 2050)(-50 2100);
WIRE 17 -1 (-50 2100)(-50 2150);
WIRE 17 -1 (-50 2150)(-50 2200);
WIRE 17 -1 (-50 2200)(-50 2250);
WIRE 17 -1 (-50 2250)(-50 2300);
WIRE 17 -1 (-50 2300)(-50 2350);
WIRE 17 -1 (-50 2350)(-50 2400);
WIRE 17 -1 (-50 2400)(-50 2450);
WIRE 17 -1 (-50 2450)(-50 2500);
WIRE 17 -1 (-50 2500)(-50 2550);
WIRE 17 -1 (-50 2550)(-50 2600);
WIRE 17 -1 (-50 2600)(-50 2650);
WIRE 17 -1 (-50 2650)(-50 2700);
WIRE 17 -1 (-50 2700)(-50 2750);
WIRE 17 -1 (-50 2750)(-50 2800);
WIRE 17 -1 (-50 2800)(-50 2850);
WIRE 17 -1 (-50 2850)(-50 2900);
WIRE 17 -1 (-50 2900)(-50 2950);
WIRE 17 -1 (-50 2950)(-50 3000);
WIRE 17 -1 (-50 3000)(-50 3050);
WIRE 17 -1 (-50 3050)(-50 3100);
WIRE 17 -1 (-50 3100)(-50 3150);
WIRE 17 -1 (-50 3150)(-50 3200);
WIRE 17 -1 (-50 3200)(-50 3250);
WIRE 17 -1 (-50 3250)(-50 3300);
WIRE 17 -1 (-50 3300)(-50 3350);
WIRE 17 -1 (-50 3350)(-50 3400);
WIRE 17 -1 (-50 3400)(-50 3450);
WIRE 17 -1 (-50 3450)(-50 3500);
WIRE 17 -1 (-50 3500)(-50 3550);
WIRE 17 -1 (-50 3550)(-50 3600);
WIRE 17 -1 (-50 3600)(-50 3650);
WIRE 17 -1 (-50 3650)(-50 3700);
WIRE 17 -1 (-50 3700)(-50 3750);
WIRE 17 -1 (-50 3750)(-50 3800);
WIRE 17 -1 (-50 3800)(-50 3850);
WIRE 17 -1 (-50 3850)(-50 3900);
WIRE 17 -1 (-50 3900)(-50 3950);
WIRE 17 -1 (-50 3950)(-50 4000);
WIRE 17 -1 (-50 4000)(-50 4050);
WIRE 17 -1 (-50 4050)(-50 4100);
WIRE 17 -1 (-50 4100)(-50 4150);
WIRE 17 -1 (-50 4150)(-50 4200);
WIRE 17 -1 (-50 4200)(-50 4250);
WIRE 17 -1 (-50 4250)(-50 4300);
WIRE 17 -1 (-50 4300)(-50 4350);
WIRE 17 -1 (-50 4350)(-50 4400);
WIRE 17 -1 (-50 4400)(-50 4450);
WIRE 17 -1 (-50 4450)(-50 4500);
WIRE 17 -1 (-50 4500)(-50 4525);
WIRE 17 -1 (450 4525)(-50 4525);
FORCEPROP 2 LAST SIG_NAME M_K_DQ<63:0>
J 0
(40 4535);
DISPLAY 0.617021 (40 4535);
PAINT ORANGE (40 4535);
WIRE 17 -1 (-1650 2950)(-1650 3000);
WIRE 17 -1 (-1650 2900)(-1650 2950);
WIRE 17 -1 (-1650 3000)(-1650 3025);
WIRE 17 -1 (-1650 3025)(-2200 3025);
FORCEPROP 2 LAST SIG_NAME M_K_CS_N<7:0>
J 0
(-2175 3035);
DISPLAY 0.617021 (-2175 3035);
PAINT ORANGE (-2175 3035);
WIRE 17 -1 (-1650 2850)(-1650 2900);
WIRE 17 -1 (-1650 2350)(-1650 2400);
WIRE 17 -1 (-1650 2300)(-1650 2350);
WIRE 17 -1 (-1650 2400)(-1650 2450);
WIRE 17 -1 (-1650 2450)(-1650 2475);
WIRE 17 -1 (-1650 2250)(-1650 2300);
WIRE 17 -1 (-1650 2200)(-1650 2250);
WIRE 17 -1 (-1650 2475)(-2200 2475);
FORCEPROP 2 LAST SIG_NAME M_K_ECC<7:0>
J 0
(-2175 2485);
DISPLAY 0.617021 (-2175 2485);
PAINT ORANGE (-2175 2485);
WIRE 17 -1 (-1650 2150)(-1650 2200);
WIRE 17 -1 (-1650 2100)(-1650 2150);
WIRE 17 -1 (-1650 2750)(-1650 2775);
WIRE 17 -1 (-1650 2700)(-1650 2750);
WIRE 17 -1 (-1650 2775)(-2200 2775);
FORCEPROP 2 LAST SIG_NAME M_K_CKE<3:0>
J 0
(-2175 2785);
DISPLAY 0.617021 (-2175 2785);
PAINT ORANGE (-2175 2785);
WIRE 17 -1 (-1650 2550)(-1650 2600);
WIRE 17 -1 (-1650 2600)(-1650 2625);
WIRE 17 -1 (-1650 2625)(-2200 2625);
FORCEPROP 2 LAST SIG_NAME M_K_ODT<3:0>
J 0
(-2175 2635);
DISPLAY 0.617021 (-2175 2635);
PAINT ORANGE (-2175 2635);
WIRE 17 -1 (-1650 3500)(-1650 3550);
WIRE 17 -1 (-1650 3575)(-1650 3550);
WIRE 17 -1 (-1650 3575)(-2200 3575);
FORCEPROP 2 LAST SIG_NAME M_K_BA<1:0>
J 0
(-2175 3585);
DISPLAY 0.617021 (-2175 3585);
PAINT ORANGE (-2175 3585);
WIRE 17 -1 (-1650 3650)(-1650 3700);
WIRE 17 -1 (-1650 3700)(-1650 3750);
WIRE 17 -1 (-1650 3750)(-1650 3800);
WIRE 17 -1 (-1650 3800)(-1650 3850);
WIRE 17 -1 (-1650 3850)(-1650 3900);
WIRE 17 -1 (-1650 3900)(-1650 3950);
WIRE 17 -1 (-1650 3950)(-1650 4000);
WIRE 17 -1 (-1650 4000)(-1650 4050);
WIRE 17 -1 (-1650 4050)(-1650 4100);
WIRE 17 -1 (-1650 4100)(-1650 4150);
WIRE 17 -1 (-1650 4150)(-1650 4200);
WIRE 17 -1 (-1650 4200)(-1650 4250);
WIRE 17 -1 (-1650 4250)(-1650 4300);
WIRE 17 -1 (-1650 4300)(-1650 4350);
WIRE 17 -1 (-1650 4350)(-1650 4400);
WIRE 17 -1 (-1650 4400)(-1650 4450);
WIRE 17 -1 (-1650 4450)(-1650 4500);
WIRE 17 -1 (-1650 4500)(-1650 4525);
WIRE 17 -1 (-2200 4525)(-1650 4525);
FORCEPROP 2 LAST SIG_NAME M_K_MA<17:0>
J 0
(-2175 4535);
DISPLAY 0.617021 (-2175 4535);
PAINT ORANGE (-2175 4535);
WIRE 17 -1 (-1650 3400)(-1650 3450);
WIRE 17 -1 (-1650 3475)(-1650 3450);
WIRE 17 -1 (-1650 3475)(-2200 3475);
FORCEPROP 2 LAST SIG_NAME M_K_BG<1:0>
J 0
(-2175 3485);
DISPLAY 0.617021 (-2175 3485);
PAINT ORANGE (-2175 3485);
WIRE 17 -1 (-2000 3375)(-2000 3300);
WIRE 17 -1 (-2000 3375)(-2600 3375);
FORCEPROP 2 LAST SIG_NAME M_K_CLK_DP<3:0>
J 0
(-2550 3385);
DISPLAY 0.617021 (-2550 3385);
PAINT ORANGE (-2550 3385);
WIRE 17 -1 (-2000 3300)(-2000 3200);
WIRE 17 -1 (2350 3150)(2350 3250);
WIRE 17 -1 (2350 3250)(2350 3350);
WIRE 17 -1 (2350 3350)(2350 3450);
WIRE 17 -1 (2350 3450)(2350 3550);
WIRE 17 -1 (2350 3550)(2350 3650);
WIRE 17 -1 (2350 3650)(2350 3750);
WIRE 17 -1 (2350 3750)(2350 3850);
WIRE 17 -1 (2350 3850)(2350 3950);
WIRE 17 -1 (2350 3950)(2350 4050);
WIRE 17 -1 (2350 4050)(2350 4150);
WIRE 17 -1 (2350 4150)(2350 4250);
WIRE 17 -1 (2350 4250)(2350 4350);
WIRE 17 -1 (2350 4350)(2350 4450);
WIRE 17 -1 (2350 4450)(2350 4550);
WIRE 17 -1 (2350 4550)(2350 4650);
WIRE 17 -1 (2350 4650)(2350 4750);
WIRE 17 -1 (2350 4750)(2350 4850);
WIRE 17 -1 (2350 4850)(2350 4875);
WIRE 17 -1 (3150 4875)(2350 4875);
FORCEPROP 2 LAST SIG_NAME M_K_DQS_DP<17:0>
J 0
(2600 4885);
DISPLAY 0.617021 (2600 4885);
PAINT ORANGE (2600 4885);
WIRE 17 -1 (2550 3100)(2550 3200);
WIRE 17 -1 (2550 3200)(2550 3300);
WIRE 17 -1 (2550 3300)(2550 3400);
WIRE 17 -1 (2550 3400)(2550 3500);
WIRE 17 -1 (2550 3500)(2550 3600);
WIRE 17 -1 (2550 3600)(2550 3700);
WIRE 17 -1 (2550 3700)(2550 3800);
WIRE 17 -1 (2550 3800)(2550 3900);
WIRE 17 -1 (2550 3900)(2550 4000);
WIRE 17 -1 (2550 4000)(2550 4100);
WIRE 17 -1 (2550 4100)(2550 4200);
WIRE 17 -1 (2550 4200)(2550 4300);
WIRE 17 -1 (2550 4300)(2550 4400);
WIRE 17 -1 (2550 4400)(2550 4500);
WIRE 17 -1 (2550 4500)(2550 4600);
WIRE 17 -1 (2550 4600)(2550 4700);
WIRE 17 -1 (2550 4700)(2550 4800);
WIRE 17 -1 (2550 4800)(2550 4825);
WIRE 17 -1 (3150 4825)(2550 4825);
FORCEPROP 2 LAST SIG_NAME M_K_DQS_DN<17:0>
J 0
(2600 4835);
DISPLAY 0.617021 (2600 4835);
PAINT ORANGE (2600 4835);
WIRE 16 -1 (-1350 1575)(-1500 1575);
WIRE 16 -1 (-1500 1625)(-1500 1575);
WIRE 16 -1 (-1500 1625)(-1350 1625);
WIRE 16 -1 (-3500 1625)(-1500 1625);
WIRE 16 -1 (-3500 1625)(-3500 1525);
WIRE 16 -1 (750 2225)(950 2225);
WIRE 16 -1 (750 2225)(750 2275);
WIRE 16 -1 (750 2275)(950 2275);
WIRE 16 -1 (600 2275)(750 2275);
WIRE 16 -1 (600 2375)(600 2275);
WIRE 16 -1 (750 2375)(950 2375);
WIRE 16 -1 (750 2425)(750 2375);
WIRE 16 -1 (750 2425)(950 2425);
WIRE 16 -1 (750 2475)(750 2425);
WIRE 16 -1 (750 2475)(950 2475);
WIRE 16 -1 (750 2475)(750 2525);
WIRE 16 -1 (750 2575)(750 2525);
WIRE 16 -1 (750 2525)(950 2525);
WIRE 16 -1 (750 2575)(950 2575);
WIRE 16 -1 (750 2675)(750 2575);
WIRE 16 -1 (2700 3175)(2900 3175);
WIRE 16 -1 (2700 3125)(2700 3175);
WIRE 16 -1 (2700 3125)(2900 3125);
WIRE 16 -1 (2700 3075)(2700 3125);
WIRE 16 -1 (2700 3075)(2900 3075);
WIRE 16 -1 (2700 3025)(2700 3075);
WIRE 16 -1 (2700 3025)(2900 3025);
WIRE 16 -1 (2700 2975)(2700 3025);
WIRE 16 -1 (2700 2975)(2900 2975);
WIRE 16 -1 (2700 2925)(2700 2975);
WIRE 16 -1 (2700 2925)(2900 2925);
WIRE 16 -1 (2700 2875)(2700 2925);
WIRE 16 -1 (2700 2875)(2900 2875);
WIRE 16 -1 (2700 2825)(2700 2875);
WIRE 16 -1 (2700 2825)(2900 2825);
WIRE 16 -1 (2700 2775)(2700 2825);
WIRE 16 -1 (2700 2775)(2900 2775);
WIRE 16 -1 (2700 2725)(2700 2775);
WIRE 16 -1 (2700 2725)(2900 2725);
WIRE 16 -1 (2700 2675)(2700 2725);
WIRE 16 -1 (2700 2675)(2900 2675);
WIRE 16 -1 (2700 2625)(2700 2675);
WIRE 16 -1 (2700 2625)(2900 2625);
WIRE 16 -1 (2700 2575)(2700 2625);
WIRE 16 -1 (2700 2575)(2900 2575);
WIRE 16 -1 (2700 2525)(2700 2575);
WIRE 16 -1 (2700 2525)(2900 2525);
WIRE 16 -1 (2700 2475)(2700 2525);
WIRE 16 -1 (2700 2475)(2900 2475);
WIRE 16 -1 (2700 2425)(2700 2475);
WIRE 16 -1 (2700 2425)(2900 2425);
WIRE 16 -1 (2700 2375)(2700 2425);
WIRE 16 -1 (2700 2375)(2900 2375);
WIRE 16 -1 (2700 2325)(2700 2375);
WIRE 16 -1 (2700 2325)(2900 2325);
WIRE 16 -1 (2700 2275)(2700 2325);
WIRE 16 -1 (2700 2275)(2900 2275);
WIRE 16 -1 (2700 2225)(2700 2275);
WIRE 16 -1 (2700 2225)(2900 2225);
WIRE 16 -1 (2700 2175)(2700 2225);
WIRE 16 -1 (2700 2175)(2900 2175);
WIRE 16 -1 (2700 2125)(2700 2175);
WIRE 16 -1 (2700 2125)(2900 2125);
WIRE 16 -1 (2700 2075)(2700 2125);
WIRE 16 -1 (2700 2075)(2900 2075);
WIRE 16 -1 (2700 2025)(2700 2075);
WIRE 16 -1 (2700 2025)(2900 2025);
WIRE 16 -1 (2700 1975)(2700 2025);
WIRE 16 -1 (2700 1975)(2900 1975);
WIRE 16 -1 (2700 1925)(2700 1975);
WIRE 16 -1 (2700 1925)(2900 1925);
WIRE 16 -1 (2700 1875)(2700 1925);
WIRE 16 -1 (2700 1875)(2900 1875);
WIRE 16 -1 (2700 1825)(2700 1875);
WIRE 16 -1 (2700 1825)(2900 1825);
WIRE 16 -1 (2700 1775)(2700 1825);
WIRE 16 -1 (2700 1775)(2900 1775);
WIRE 16 -1 (2700 1725)(2700 1775);
WIRE 16 -1 (2700 1725)(2900 1725);
WIRE 16 -1 (2700 1675)(2700 1725);
WIRE 16 -1 (2700 1675)(2900 1675);
WIRE 16 -1 (2700 1625)(2700 1675);
WIRE 16 -1 (2700 1625)(2900 1625);
WIRE 16 -1 (2700 1575)(2700 1625);
WIRE 16 -1 (2700 1575)(2900 1575);
WIRE 16 -1 (2700 1525)(2700 1575);
WIRE 16 -1 (2700 1525)(2900 1525);
WIRE 16 -1 (2700 1475)(2700 1525);
WIRE 16 -1 (2700 1475)(2900 1475);
WIRE 16 -1 (2700 1425)(2700 1475);
WIRE 16 -1 (2700 1425)(2900 1425);
WIRE 16 -1 (2700 1375)(2700 1425);
WIRE 16 -1 (2700 1375)(2900 1375);
WIRE 16 -1 (2700 1325)(2700 1375);
WIRE 16 -1 (2700 1325)(2900 1325);
WIRE 16 -1 (2700 1275)(2700 1325);
WIRE 16 -1 (2700 1275)(2900 1275);
WIRE 16 -1 (2700 1225)(2700 1275);
WIRE 16 -1 (2700 1225)(2900 1225);
WIRE 16 -1 (2700 1175)(2700 1225);
WIRE 16 -1 (2700 1175)(2900 1175);
WIRE 16 -1 (2700 1125)(2700 1175);
WIRE 16 -1 (2700 1125)(2900 1125);
WIRE 16 -1 (2700 1075)(2700 1125);
WIRE 16 -1 (2700 1075)(2900 1075);
WIRE 16 -1 (2700 1025)(2700 1075);
WIRE 16 -1 (2700 1025)(2900 1025);
WIRE 16 -1 (2700 975)(2700 1025);
WIRE 16 -1 (2700 975)(2900 975);
WIRE 16 -1 (2700 925)(2700 975);
WIRE 16 -1 (2700 925)(2900 925);
WIRE 16 -1 (2700 875)(2700 925);
WIRE 16 -1 (2700 875)(2900 875);
WIRE 16 -1 (2700 775)(2700 875);
WIRE 16 -1 (4100 3125)(4100 3175);
WIRE 16 -1 (4100 3075)(4100 3125);
WIRE 16 -1 (4100 3125)(3900 3125);
WIRE 16 -1 (4100 3175)(3900 3175);
WIRE 16 -1 (4100 3025)(4100 3075);
WIRE 16 -1 (4100 3075)(3900 3075);
WIRE 16 -1 (4100 2975)(4100 3025);
WIRE 16 -1 (4100 3025)(3900 3025);
WIRE 16 -1 (4100 2925)(4100 2975);
WIRE 16 -1 (4100 2975)(3900 2975);
WIRE 16 -1 (4100 2875)(4100 2925);
WIRE 16 -1 (4100 2925)(3900 2925);
WIRE 16 -1 (4100 2825)(4100 2875);
WIRE 16 -1 (4100 2875)(3900 2875);
WIRE 16 -1 (4100 2775)(4100 2825);
WIRE 16 -1 (4100 2825)(3900 2825);
WIRE 16 -1 (4100 2725)(4100 2775);
WIRE 16 -1 (4100 2775)(3900 2775);
WIRE 16 -1 (4100 2675)(4100 2725);
WIRE 16 -1 (4100 2725)(3900 2725);
WIRE 16 -1 (4100 2625)(4100 2675);
WIRE 16 -1 (4100 2675)(3900 2675);
WIRE 16 -1 (4100 2575)(4100 2625);
WIRE 16 -1 (4100 2625)(3900 2625);
WIRE 16 -1 (4100 2525)(4100 2575);
WIRE 16 -1 (4100 2575)(3900 2575);
WIRE 16 -1 (4100 2475)(4100 2525);
WIRE 16 -1 (4100 2525)(3900 2525);
WIRE 16 -1 (4100 2425)(4100 2475);
WIRE 16 -1 (4100 2475)(3900 2475);
WIRE 16 -1 (4100 2375)(4100 2425);
WIRE 16 -1 (4100 2425)(3900 2425);
WIRE 16 -1 (4100 2325)(4100 2375);
WIRE 16 -1 (4100 2375)(3900 2375);
WIRE 16 -1 (4100 2275)(4100 2325);
WIRE 16 -1 (4100 2325)(3900 2325);
WIRE 16 -1 (4100 2225)(4100 2275);
WIRE 16 -1 (4100 2275)(3900 2275);
WIRE 16 -1 (4100 2175)(4100 2225);
WIRE 16 -1 (4100 2225)(3900 2225);
WIRE 16 -1 (4100 2125)(4100 2175);
WIRE 16 -1 (4100 2175)(3900 2175);
WIRE 16 -1 (4100 2075)(4100 2125);
WIRE 16 -1 (4100 2125)(3900 2125);
WIRE 16 -1 (4100 2025)(4100 2075);
WIRE 16 -1 (4100 2075)(3900 2075);
WIRE 16 -1 (4100 1975)(4100 2025);
WIRE 16 -1 (4100 2025)(3900 2025);
WIRE 16 -1 (4100 1925)(4100 1975);
WIRE 16 -1 (4100 1975)(3900 1975);
WIRE 16 -1 (4100 1875)(4100 1925);
WIRE 16 -1 (4100 1925)(3900 1925);
WIRE 16 -1 (4100 1825)(4100 1875);
WIRE 16 -1 (4100 1875)(3900 1875);
WIRE 16 -1 (4100 1775)(4100 1825);
WIRE 16 -1 (4100 1825)(3900 1825);
WIRE 16 -1 (4100 1725)(4100 1775);
WIRE 16 -1 (4100 1775)(3900 1775);
WIRE 16 -1 (4100 1675)(4100 1725);
WIRE 16 -1 (4100 1725)(3900 1725);
WIRE 16 -1 (4100 1625)(4100 1675);
WIRE 16 -1 (4100 1675)(3900 1675);
WIRE 16 -1 (4100 1575)(4100 1625);
WIRE 16 -1 (4100 1625)(3900 1625);
WIRE 16 -1 (4100 1525)(4100 1575);
WIRE 16 -1 (4100 1575)(3900 1575);
WIRE 16 -1 (4100 1475)(4100 1525);
WIRE 16 -1 (4100 1525)(3900 1525);
WIRE 16 -1 (4100 1425)(4100 1475);
WIRE 16 -1 (4100 1475)(3900 1475);
WIRE 16 -1 (4100 1375)(4100 1425);
WIRE 16 -1 (4100 1425)(3900 1425);
WIRE 16 -1 (4100 1325)(4100 1375);
WIRE 16 -1 (4100 1375)(3900 1375);
WIRE 16 -1 (4100 1275)(4100 1325);
WIRE 16 -1 (4100 1325)(3900 1325);
WIRE 16 -1 (4100 1225)(4100 1275);
WIRE 16 -1 (4100 1275)(3900 1275);
WIRE 16 -1 (4100 1175)(4100 1225);
WIRE 16 -1 (4100 1225)(3900 1225);
WIRE 16 -1 (4100 1125)(4100 1175);
WIRE 16 -1 (4100 1175)(3900 1175);
WIRE 16 -1 (4100 1075)(4100 1125);
WIRE 16 -1 (4100 1125)(3900 1125);
WIRE 16 -1 (4100 1025)(4100 1075);
WIRE 16 -1 (4100 1075)(3900 1075);
WIRE 16 -1 (4100 975)(4100 1025);
WIRE 16 -1 (4100 1025)(3900 1025);
WIRE 16 -1 (4100 925)(4100 975);
WIRE 16 -1 (4100 975)(3900 975);
WIRE 16 -1 (4100 875)(4100 925);
WIRE 16 -1 (4100 925)(3900 925);
WIRE 16 -1 (4100 775)(4100 875);
WIRE 16 -1 (4100 875)(3900 875);
WIRE 16 -1 (2150 2525)(2150 2575);
WIRE 16 -1 (2150 2525)(1950 2525);
WIRE 16 -1 (2150 2575)(2150 2750);
WIRE 16 -1 (2150 2575)(1950 2575);
WIRE 16 -1 (-3000 1025)(-3000 925);
WIRE 16 -1 (-1350 1525)(-1550 1525);
WIRE 16 -1 (-1550 1525)(-1550 1675);
WIRE 16 -1 (-1550 1675)(-1350 1675);
WIRE 16 -1 (-3500 1675)(-1550 1675);
WIRE 16 -1 (-3500 1675)(-3500 1775);
WIRE 16 -1 (750 875)(950 875);
WIRE 16 -1 (750 875)(750 925);
WIRE 16 -1 (750 925)(950 925);
WIRE 16 -1 (750 925)(750 975);
WIRE 16 -1 (750 975)(750 1025);
WIRE 16 -1 (750 975)(950 975);
WIRE 16 -1 (750 1025)(950 1025);
WIRE 16 -1 (750 1025)(750 1075);
WIRE 16 -1 (750 1075)(950 1075);
WIRE 16 -1 (750 1075)(750 1125);
WIRE 16 -1 (750 1125)(950 1125);
WIRE 16 -1 (750 1125)(750 1175);
WIRE 16 -1 (750 1175)(950 1175);
WIRE 16 -1 (750 1175)(750 1225);
WIRE 16 -1 (750 1225)(950 1225);
WIRE 16 -1 (750 1225)(750 1275);
WIRE 16 -1 (750 1275)(950 1275);
WIRE 16 -1 (750 1275)(750 1325);
WIRE 16 -1 (750 1325)(950 1325);
WIRE 16 -1 (750 1325)(750 1375);
WIRE 16 -1 (750 1375)(950 1375);
WIRE 16 -1 (750 1375)(750 1425);
WIRE 16 -1 (750 1425)(950 1425);
WIRE 16 -1 (750 1425)(750 1475);
WIRE 16 -1 (750 1475)(950 1475);
WIRE 16 -1 (750 1475)(750 1525);
WIRE 16 -1 (750 1525)(750 1575);
WIRE 16 -1 (750 1525)(950 1525);
WIRE 16 -1 (750 1575)(950 1575);
WIRE 16 -1 (750 1575)(750 1625);
WIRE 16 -1 (750 1625)(950 1625);
WIRE 16 -1 (750 1625)(750 1675);
WIRE 16 -1 (750 1675)(950 1675);
WIRE 16 -1 (750 1675)(750 1725);
WIRE 16 -1 (750 1725)(950 1725);
WIRE 16 -1 (750 1725)(750 1775);
WIRE 16 -1 (750 1775)(950 1775);
WIRE 16 -1 (750 1775)(750 1825);
WIRE 16 -1 (750 1825)(950 1825);
WIRE 16 -1 (750 1825)(750 1875);
WIRE 16 -1 (750 1875)(950 1875);
WIRE 16 -1 (750 1875)(750 1925);
WIRE 16 -1 (750 1925)(950 1925);
WIRE 16 -1 (750 1925)(750 1975);
WIRE 16 -1 (750 1975)(950 1975);
WIRE 16 -1 (750 1975)(750 2025);
WIRE 16 -1 (750 2025)(750 2075);
WIRE 16 -1 (750 2025)(950 2025);
WIRE 16 -1 (750 2075)(950 2075);
WIRE 16 -1 (750 2075)(750 2125);
WIRE 16 -1 (750 2125)(950 2125);
WIRE 16 -1 (325 2125)(750 2125);
WIRE 16 -1 (325 2225)(325 2125);
WIRE 16 -1 (-1800 2175)(-1800 1875);
WIRE 16 -1 (-1800 2175)(-2525 2175);
FORCEPROP 2 LAST SIG_NAME FM_DIMM_EVENT_COD_N
J 0
(-2472 2192);
DISPLAY 0.617021 (-2472 2192);
PAINT ORANGE (-2472 2192);
WIRE 16 -1 (-1800 1875)(-1350 1875);
WIRE 16 -1 (2450 4775)(2050 4775);
WIRE 16 -1 (2450 4675)(2050 4675);
WIRE 16 -1 (2250 4825)(2050 4825);
WIRE 16 -1 (2250 4725)(2050 4725);
WIRE 16 -1 (2250 4625)(2050 4625);
WIRE 16 -1 (2450 4575)(2050 4575);
WIRE 16 -1 (2450 4475)(2050 4475);
WIRE 16 -1 (2450 4375)(2050 4375);
WIRE 16 -1 (2450 4275)(2050 4275);
WIRE 16 -1 (2450 4175)(2050 4175);
WIRE 16 -1 (2250 4525)(2050 4525);
WIRE 16 -1 (2250 4425)(2050 4425);
WIRE 16 -1 (2250 4325)(2050 4325);
WIRE 16 -1 (2250 4225)(2050 4225);
WIRE 16 -1 (2250 4125)(2050 4125);
WIRE 16 -1 (2450 3975)(2050 3975);
WIRE 16 -1 (2450 3875)(2050 3875);
WIRE 16 -1 (2450 3775)(2050 3775);
WIRE 16 -1 (2450 3675)(2050 3675);
WIRE 16 -1 (2450 4075)(2050 4075);
WIRE 16 -1 (2250 4025)(2050 4025);
WIRE 16 -1 (2250 3925)(2050 3925);
WIRE 16 -1 (2250 3825)(2050 3825);
WIRE 16 -1 (2250 3725)(2050 3725);
WIRE 16 -1 (2250 3625)(2050 3625);
WIRE 16 -1 (2450 3575)(2050 3575);
WIRE 16 -1 (2450 3475)(2050 3475);
WIRE 16 -1 (2450 3375)(2050 3375);
WIRE 16 -1 (2450 3275)(2050 3275);
WIRE 16 -1 (2450 3175)(2050 3175);
WIRE 16 -1 (2450 3075)(2050 3075);
WIRE 16 -1 (2250 3525)(2050 3525);
WIRE 16 -1 (2250 3425)(2050 3425);
WIRE 16 -1 (2250 3325)(2050 3325);
WIRE 16 -1 (2250 3225)(2050 3225);
WIRE 16 -1 (2250 3125)(2050 3125);
WIRE 16 -1 (-150 4425)(-350 4425);
WIRE 16 -1 (-150 4325)(-350 4325);
WIRE 16 -1 (-150 4225)(-350 4225);
WIRE 16 -1 (-150 4175)(-350 4175);
WIRE 16 -1 (-150 4125)(-350 4125);
WIRE 16 -1 (-150 4275)(-350 4275);
WIRE 16 -1 (-150 4375)(-350 4375);
WIRE 16 -1 (-150 4475)(-350 4475);
WIRE 16 -1 (-1350 4275)(-1550 4275);
WIRE 16 -1 (-1350 4425)(-1550 4425);
WIRE 16 -1 (-1350 4375)(-1550 4375);
WIRE 16 -1 (-1350 4325)(-1550 4325);
WIRE 16 -1 (-1350 4175)(-1550 4175);
WIRE 16 -1 (-1350 4125)(-1550 4125);
WIRE 16 -1 (-1350 4475)(-1550 4475);
WIRE 16 -1 (-1350 4225)(-1550 4225);
WIRE 16 -1 (-150 3675)(-350 3675);
WIRE 16 -1 (-150 3725)(-350 3725);
WIRE 16 -1 (-150 3775)(-350 3775);
WIRE 16 -1 (-150 3825)(-350 3825);
WIRE 16 -1 (-150 3875)(-350 3875);
WIRE 16 -1 (-150 3925)(-350 3925);
WIRE 16 -1 (-150 3975)(-350 3975);
WIRE 16 -1 (-150 4025)(-350 4025);
WIRE 16 -1 (-150 3625)(-350 3625);
WIRE 16 -1 (-150 4075)(-350 4075);
WIRE 16 -1 (-150 3375)(-350 3375);
WIRE 16 -1 (-150 3325)(-350 3325);
WIRE 16 -1 (-150 3075)(-350 3075);
WIRE 16 -1 (-150 3225)(-350 3225);
WIRE 16 -1 (-150 3125)(-350 3125);
WIRE 16 -1 (-150 3175)(-350 3175);
WIRE 16 -1 (-150 3275)(-350 3275);
WIRE 16 -1 (-150 3425)(-350 3425);
WIRE 16 -1 (-150 3475)(-350 3475);
WIRE 16 -1 (-150 3525)(-350 3525);
WIRE 16 -1 (-150 3575)(-350 3575);
WIRE 16 -1 (-150 2625)(-350 2625);
WIRE 16 -1 (-150 2675)(-350 2675);
WIRE 16 -1 (-150 2575)(-350 2575);
WIRE 16 -1 (-150 2825)(-350 2825);
WIRE 16 -1 (-150 2875)(-350 2875);
WIRE 16 -1 (-150 2925)(-350 2925);
WIRE 16 -1 (-150 2975)(-350 2975);
WIRE 16 -1 (-150 3025)(-350 3025);
WIRE 16 -1 (-150 2725)(-350 2725);
WIRE 16 -1 (-150 2775)(-350 2775);
WIRE 16 -1 (-150 2175)(-350 2175);
WIRE 16 -1 (-150 2075)(-350 2075);
WIRE 16 -1 (-150 2125)(-350 2125);
WIRE 16 -1 (-150 2225)(-350 2225);
WIRE 16 -1 (-150 2275)(-350 2275);
WIRE 16 -1 (-150 2325)(-350 2325);
WIRE 16 -1 (-150 2375)(-350 2375);
WIRE 16 -1 (-150 2425)(-350 2425);
WIRE 16 -1 (-150 2475)(-350 2475);
WIRE 16 -1 (-150 2525)(-350 2525);
WIRE 16 -1 (-1350 3175)(-1900 3175);
WIRE 16 -1 (-1350 3275)(-1900 3275);
WIRE 16 -1 (-1350 3375)(-1550 3375);
WIRE 16 -1 (-1350 3425)(-1550 3425);
WIRE 16 -1 (-1350 3725)(-1550 3725);
WIRE 16 -1 (-1350 3475)(-1550 3475);
WIRE 16 -1 (-1350 4075)(-1550 4075);
WIRE 16 -1 (-1350 4025)(-1550 4025);
WIRE 16 -1 (-1350 3975)(-1550 3975);
WIRE 16 -1 (-1350 3925)(-1550 3925);
WIRE 16 -1 (-1350 3875)(-1550 3875);
WIRE 16 -1 (-1350 3825)(-1550 3825);
WIRE 16 -1 (-1350 3775)(-1550 3775);
WIRE 16 -1 (-1350 3675)(-1550 3675);
WIRE 16 -1 (-1350 3625)(-1550 3625);
WIRE 16 -1 (-1350 3525)(-1550 3525);
WIRE 16 -1 (-1500 3075)(-1500 3025);
WIRE 16 -1 (-1500 3075)(-2200 3075);
FORCEPROP 2 LAST SIG_NAME M_K_C<2>
J 0
(-2175 3085);
DISPLAY 0.617021 (-2175 3085);
PAINT ORANGE (-2175 3085);
WIRE 16 -1 (-1500 3025)(-1350 3025);
WIRE 16 -1 (-1350 2375)(-1550 2375);
WIRE 16 -1 (-1350 2825)(-1550 2825);
WIRE 16 -1 (-1350 2675)(-1550 2675);
WIRE 16 -1 (-1350 2575)(-1550 2575);
WIRE 16 -1 (-1350 2525)(-1550 2525);
WIRE 16 -1 (-1350 2425)(-1550 2425);
WIRE 16 -1 (-1350 2725)(-1550 2725);
WIRE 16 -1 (-1350 2075)(-1550 2075);
WIRE 16 -1 (-1350 2125)(-1550 2125);
WIRE 16 -1 (-1350 2175)(-1550 2175);
WIRE 16 -1 (-1350 2225)(-1550 2225);
WIRE 16 -1 (-1350 2275)(-1550 2275);
WIRE 16 -1 (-1350 2325)(-1550 2325);
WIRE 16 -1 (-1350 2875)(-1550 2875);
WIRE 16 -1 (-1350 2925)(-1550 2925);
WIRE 16 -1 (-1350 2975)(-1550 2975);
WIRE 16 -1 (-1750 1925)(-1750 2375);
WIRE 16 -1 (-1350 1925)(-1750 1925);
WIRE 16 -1 (-1750 2375)(-2200 2375);
FORCEPROP 2 LAST SIG_NAME M_KLM_RST_N
J 0
(-2175 2385);
DISPLAY 0.617021 (-2175 2385);
PAINT ORANGE (-2175 2385);
WIRE 16 -1 (-1700 1975)(-1700 2425);
WIRE 16 -1 (-1350 1975)(-1700 1975);
WIRE 16 -1 (-1700 2425)(-2200 2425);
FORCEPROP 2 LAST SIG_NAME M_K_PAR
J 0
(-2175 2435);
DISPLAY 0.617021 (-2175 2435);
PAINT ORANGE (-2175 2435);
WIRE 16 -1 (-150 1775)(-350 1775);
WIRE 16 -1 (-150 1575)(-350 1575);
WIRE 16 -1 (-150 1625)(-350 1625);
WIRE 16 -1 (-150 1675)(-350 1675);
WIRE 16 -1 (-150 1725)(-350 1725);
WIRE 16 -1 (-150 1825)(-350 1825);
WIRE 16 -1 (-150 1875)(-350 1875);
WIRE 16 -1 (-150 1925)(-350 1925);
WIRE 16 -1 (-150 1975)(-350 1975);
WIRE 16 -1 (-150 2025)(-350 2025);
WIRE 16 -1 (-150 1325)(-350 1325);
WIRE 16 -1 (-150 1525)(-350 1525);
WIRE 16 -1 (-150 1475)(-350 1475);
WIRE 16 -1 (-150 1425)(-350 1425);
WIRE 16 -1 (-150 1375)(-350 1375);
WIRE 16 -1 (-1350 1775)(-2350 1775);
FORCEPROP 2 LAST SIG_NAME M_K_ACT_N
J 0
(-2300 1785);
DISPLAY 0.617021 (-2300 1785);
PAINT ORANGE (-2300 1785);
WIRE 16 -1 (-1350 1825)(-2375 1825);
FORCEPROP 2 LAST SIG_NAME M_K_ALERT_N
J 0
(-2325 1835);
DISPLAY 0.617021 (-2325 1835);
PAINT ORANGE (-2325 1835);
WIRE 16 -1 (-1350 1475)(-2150 1475);
WIRE 16 -1 (-2150 1425)(-1350 1425);
FORCEPROP 2 LAST SIG_NAME SMB_DDR_KLM_VPP_SCL
J 0
(-2110 1435);
DISPLAY 0.617021 (-2110 1435);
PAINT ORANGE (-2110 1435);
WIRE 16 -1 (-2200 1025)(-1350 1025);
FORCEPROP 2 LAST SIG_NAME FM_ADR_COMPLETE_KLM_N
J 0
(-2150 1035);
DISPLAY 0.617021 (-2150 1035);
PAINT ORANGE (-2150 1035);
WIRE 16 -1 (-1350 3125)(-2050 3125);
WIRE 16 -1 (-1350 3225)(-2050 3225);
WIRE 16 -1 (-2200 1175)(-1350 1175);
FORCEPROP 2 LAST SIG_NAME TP_CH_K_DIMM0_RFU_1
J 0
(-2150 1185);
DISPLAY 0.617021 (-2150 1185);
PAINT ORANGE (-2150 1185);
FORCEPROP 2 LASTPROP $XRERR UNIQUE?
J 0
(-2440 1175);
DISPLAY 0.638298 (-2440 1175);
PAINT MONO (-2440 1175);
DISPLAY INVISIBLE (-2440 1175);
WIRE 16 -1 (-2200 1125)(-1350 1125);
FORCEPROP 2 LAST SIG_NAME TP_CH_K_DIMM0_RFU_0
J 0
(-2150 1135);
DISPLAY 0.617021 (-2150 1135);
PAINT ORANGE (-2150 1135);
FORCEPROP 2 LASTPROP $XRERR UNIQUE?
J 0
(-2440 1125);
DISPLAY 0.638298 (-2440 1125);
PAINT MONO (-2440 1125);
DISPLAY INVISIBLE (-2440 1125);
WIRE 16 -1 (-2200 1225)(-1350 1225);
FORCEPROP 2 LAST SIG_NAME TP_CH_K_DIMM0_RFU_2
J 0
(-2150 1235);
DISPLAY 0.617021 (-2150 1235);
PAINT ORANGE (-2150 1235);
FORCEPROP 2 LASTPROP $XRERR UNIQUE?
J 0
(-2440 1225);
DISPLAY 0.638298 (-2440 1225);
PAINT MONO (-2440 1225);
DISPLAY INVISIBLE (-2440 1225);
WIRE 16 -1 (-1350 1325)(-3000 1325);
FORCEPROP 2 LAST SIG_NAME M_K_VREF
J 0
(-2100 1335);
DISPLAY 0.617021 (-2100 1335);
PAINT ORANGE (-2100 1335);
WIRE 16 -1 (-3000 1325)(-3000 1225);
WIRE 16 -1 (-3100 1325)(-3000 1325);
DOT 1 (4100 3125);
DOT 1 (4100 2975);
DOT 1 (4100 3075);
DOT 1 (4100 3025);
DOT 1 (4100 2925);
DOT 1 (4100 2875);
DOT 1 (4100 2775);
DOT 1 (4100 2825);
DOT 1 (4100 2725);
DOT 1 (4100 2625);
DOT 1 (4100 2675);
DOT 1 (4100 2575);
DOT 1 (4100 2525);
DOT 1 (4100 2475);
DOT 1 (4100 2375);
DOT 1 (4100 2425);
DOT 1 (4100 2325);
DOT 1 (4100 2275);
DOT 1 (4100 2225);
DOT 1 (4100 2075);
DOT 1 (4100 2175);
DOT 1 (4100 2125);
DOT 1 (4100 2025);
DOT 1 (4100 1975);
DOT 1 (4100 1925);
DOT 1 (4100 1825);
DOT 1 (4100 1875);
DOT 1 (4100 1725);
DOT 1 (4100 1775);
DOT 1 (4100 1675);
DOT 1 (4100 1575);
DOT 1 (4100 1625);
DOT 1 (4100 1475);
DOT 1 (4100 1525);
DOT 1 (4100 1425);
DOT 1 (4100 1325);
DOT 1 (4100 1375);
DOT 1 (4100 1275);
DOT 1 (4100 1225);
DOT 1 (4100 1175);
DOT 1 (4100 1075);
DOT 1 (4100 1125);
DOT 1 (4100 1025);
DOT 1 (4100 925);
DOT 1 (4100 975);
DOT 1 (4100 875);
DOT 1 (2700 3125);
DOT 1 (2700 2975);
DOT 1 (2700 3075);
DOT 1 (2700 3025);
DOT 1 (2700 2925);
DOT 1 (2700 2875);
DOT 1 (2700 2725);
DOT 1 (2700 2825);
DOT 1 (2700 2775);
DOT 1 (2700 2625);
DOT 1 (2700 2675);
DOT 1 (2700 2575);
DOT 1 (2700 2475);
DOT 1 (2700 2525);
DOT 1 (2700 2375);
DOT 1 (2700 2425);
DOT 1 (2700 2325);
DOT 1 (2700 2275);
DOT 1 (2700 2225);
DOT 1 (2700 2075);
DOT 1 (2700 2125);
DOT 1 (2700 2175);
DOT 1 (2700 1975);
DOT 1 (2700 2025);
DOT 1 (2700 1825);
DOT 1 (2700 1875);
DOT 1 (2700 1925);
DOT 1 (2700 1775);
DOT 1 (2700 1725);
DOT 1 (2150 2575);
DOT 1 (2700 1675);
DOT 1 (2700 1625);
DOT 1 (2700 1575);
DOT 1 (2700 1525);
DOT 1 (2700 1475);
DOT 1 (2700 1425);
DOT 1 (2700 1325);
DOT 1 (2700 1375);
DOT 1 (2700 1275);
DOT 1 (2700 1175);
DOT 1 (2700 1225);
DOT 1 (2700 1075);
DOT 1 (2700 1125);
DOT 1 (2700 925);
DOT 1 (2700 1025);
DOT 1 (2700 975);
DOT 1 (2700 875);
DOT 1 (750 2575);
DOT 1 (750 2525);
DOT 1 (750 2425);
DOT 1 (750 2275);
DOT 1 (750 1975);
DOT 1 (750 1925);
DOT 1 (750 1875);
DOT 1 (750 1825);
DOT 1 (750 1725);
DOT 1 (750 1675);
DOT 1 (750 1575);
DOT 1 (750 1525);
DOT 1 (750 1475);
DOT 1 (750 1425);
DOT 1 (750 1375);
DOT 1 (750 1325);
DOT 1 (750 1275);
DOT 1 (750 1225);
DOT 1 (750 1175);
DOT 1 (750 1075);
DOT 1 (750 1125);
DOT 1 (750 1025);
DOT 1 (750 975);
DOT 1 (750 925);
DOT 1 (-3000 1325);
DOT 1 (750 2075);
DOT 1 (750 2025);
DOT 1 (750 1775);
DOT 1 (750 1625);
DOT 1 (-1550 1675);
DOT 1 (-1500 1625);
DOT 1 (750 2125);
DOT 1 (750 2475);
FORCENOTE
SMBUS ADDR: 0XA2
(-1300 709) 0;
DISPLAY LEFT (-1300 709);
DISPLAY 1.957447 (-1300 709);
PAINT PURPLE (-1300 709);
FORCENOTE
PLACE CAP NEAR DIMM CONNECTOR
(-3688 777) 0;
DISPLAY LEFT (-3688 777);
DISPLAY 1.595745 (-3688 777);
PAINT PURPLE (-3688 777);
QUIT
